# Altium SchDoc records: 09-USBUart_PPSMUX_UARTMUX.SchDoc
|HEADER=Protel for Windows - Schematic Capture Binary File Version 5.0|Weight=2489|MinorVersion=9
|RECORD=31|FontIdCount=3|Size1=10|FontName1=Times New Roman|Size2=10|Rotation2=90|FontName2=Times New Roman|Size3=10|Underline3=T|FontName3=Times New Roman|UseMBCS=T|IsBOC=T|HotSpotGridOn=T|HotSpotGridSize=4|SheetStyle=6|SystemFont=1|BorderOn=T|TitleBlockOn=T|SheetNumberSpaceSize=12|AreaColor=16317695|SnapGridOn=T|SnapGridSize=10|VisibleGridOn=T|VisibleGridSize=10|CustomX=1500|CustomY=950|CustomXZones=6|CustomYZones=4|CustomMarginWidth=20|Display_Unit=0
|RECORD=41|OwnerPartId=-1|Color=8388608|FontID=1|IsHidden=T|Text=*|Name=CurrentTime|ReadOnlyState=1
|RECORD=41|IndexInSheet=1|OwnerPartId=-1|Color=8388608|FontID=1|IsHidden=T|Text=*|Name=CurrentDate|ReadOnlyState=1
|RECORD=41|IndexInSheet=2|OwnerPartId=-1|Color=8388608|FontID=1|IsHidden=T|Text=*|Name=Time|ReadOnlyState=1
|RECORD=41|IndexInSheet=3|OwnerPartId=-1|Color=8388608|FontID=1|IsHidden=T|Text=*|Name=Date|ReadOnlyState=1
|RECORD=41|IndexInSheet=4|OwnerPartId=-1|Color=8388608|FontID=1|IsHidden=T|Text=*|Name=DocumentFullPathAndName|ReadOnlyState=1
|RECORD=41|IndexInSheet=5|OwnerPartId=-1|Color=8388608|FontID=1|IsHidden=T|Text=*|Name=DocumentName|ReadOnlyState=1
|RECORD=41|IndexInSheet=6|OwnerPartId=-1|Color=8388608|FontID=1|IsHidden=T|Text=*|Name=ModifiedDate|ReadOnlyState=1
|RECORD=41|IndexInSheet=7|OwnerPartId=-1|Color=8388608|FontID=1|IsHidden=T|Text=*|Name=ApprovedBy|ReadOnlyState=1
|RECORD=41|IndexInSheet=8|OwnerPartId=-1|Color=8388608|FontID=1|IsHidden=T|Text=*|Name=CheckedBy|ReadOnlyState=1
|RECORD=41|IndexInSheet=9|OwnerPartId=-1|Color=8388608|FontID=1|IsHidden=T|Text=*|Name=Author|ReadOnlyState=1
|RECORD=41|IndexInSheet=10|OwnerPartId=-1|Color=8388608|FontID=1|IsHidden=T|Text=*|Name=CompanyName|ReadOnlyState=1
|RECORD=41|IndexInSheet=11|OwnerPartId=-1|Color=8388608|FontID=1|IsHidden=T|Text=*|Name=DrawnBy|ReadOnlyState=1
|RECORD=41|IndexInSheet=12|OwnerPartId=-1|Color=8388608|FontID=1|IsHidden=T|Text=*|Name=Engineer|ReadOnlyState=1
|RECORD=41|IndexInSheet=13|OwnerPartId=-1|Color=8388608|FontID=1|IsHidden=T|Text=*|Name=Organization|ReadOnlyState=1
|RECORD=41|IndexInSheet=14|OwnerPartId=-1|Color=8388608|FontID=1|IsHidden=T|Text=*|Name=Address1|ReadOnlyState=1
|RECORD=41|IndexInSheet=15|OwnerPartId=-1|Color=8388608|FontID=1|IsHidden=T|Text=*|Name=Address2|ReadOnlyState=1
|RECORD=41|IndexInSheet=16|OwnerPartId=-1|Color=8388608|FontID=1|IsHidden=T|Text=*|Name=Address3|ReadOnlyState=1
|RECORD=41|IndexInSheet=17|OwnerPartId=-1|Color=8388608|FontID=1|IsHidden=T|Text=*|Name=Address4|ReadOnlyState=1
|RECORD=41|IndexInSheet=18|OwnerPartId=-1|Color=8388608|FontID=1|IsHidden=T|Text=*|Name=Title|ReadOnlyState=1
|RECORD=41|IndexInSheet=19|OwnerPartId=-1|Color=8388608|FontID=1|IsHidden=T|Text=*|Name=DocumentNumber|ReadOnlyState=1
|RECORD=41|IndexInSheet=20|OwnerPartId=-1|Color=8388608|FontID=1|IsHidden=T|Text=*|Name=Revision|ReadOnlyState=1
|RECORD=41|IndexInSheet=21|OwnerPartId=-1|Color=8388608|FontID=1|IsHidden=T|Text=*|Name=SheetNumber|ReadOnlyState=1
|RECORD=41|IndexInSheet=22|OwnerPartId=-1|Color=8388608|FontID=1|IsHidden=T|Text=*|Name=SheetTotal|ReadOnlyState=1
|RECORD=41|IndexInSheet=23|OwnerPartId=-1|Color=8388608|FontID=1|IsHidden=T|Text=*|Name=Rule|ReadOnlyState=1
|RECORD=41|IndexInSheet=24|OwnerPartId=-1|Color=8388608|FontID=1|IsHidden=T|Text=*|Name=ImagePath|ReadOnlyState=1
|RECORD=41|IndexInSheet=25|OwnerPartId=-1|Color=8388608|FontID=1|IsHidden=T|Text=*|Name=ProjectName|ReadOnlyState=1
|RECORD=41|IndexInSheet=26|OwnerPartId=-1|Color=8388608|FontID=1|IsHidden=T|Text=*|Name=Application_BuildNumber|ReadOnlyState=1
|RECORD=1|LibReference=4bef3367ed9f9051bcb84ab46edda1c|ComponentDescription=IC USB SERIAL BASIC UART 12DFN|PartCount=2|DisplayModeCount=1|IndexInSheet=27|OwnerPartId=-1|Location.X=570|Location.Y=850|CurrentPartId=1|LibraryPath=*|SourceLibraryName=Altium Content Vault|TargetFileName=*|AreaColor=11599871|Color=128|PartIDLocked=T|DesignItemId=CMP-0248-00027-3|AllPinCount=13
|RECORD=14|OwnerIndex=28|IsNotAccesible=T|OwnerPartId=1|Location.X=590|Location.Y=760|Corner.X=720|Corner.Y=860|LineWidth=1|Color=128|AreaColor=11599871|IsSolid=T
|RECORD=2|OwnerIndex=28|OwnerPartId=1|Electrical=7|PinConglomerate=58|PinLength=20|Location.X=590|Location.Y=770|Name=3V3OUT|Designator=3|PinPropagationDelay=0.000000E+000
|RECORD=2|OwnerIndex=28|OwnerPartId=1|Electrical=7|PinConglomerate=58|PinLength=20|Location.X=590|Location.Y=850|Name=VCC|Designator=4|PinPropagationDelay=0.000000E+000
|RECORD=2|OwnerIndex=28|OwnerPartId=1|Electrical=7|PinConglomerate=58|PinLength=20|Location.X=590|Location.Y=840|Name=VCCIO|Designator=9|PinPropagationDelay=0.000000E+000
|RECORD=2|OwnerIndex=28|OwnerPartId=1|PinConglomerate=56|PinLength=20|Location.X=720|Location.Y=820|Name=C\T\S\|Designator=11|PinPropagationDelay=0.000000E+000
|RECORD=2|OwnerIndex=28|OwnerPartId=1|PinConglomerate=58|PinLength=20|Location.X=590|Location.Y=790|Name=R\E\S\E\T\|Designator=2|PinPropagationDelay=0.000000E+000
|RECORD=2|OwnerIndex=28|OwnerPartId=1|PinConglomerate=56|PinLength=20|Location.X=720|Location.Y=830|Name=R\T\S\|Designator=8|PinPropagationDelay=0.000000E+000
|RECORD=2|OwnerIndex=28|OwnerPartId=1|Electrical=1|PinConglomerate=56|PinLength=20|Location.X=720|Location.Y=800|Name=CBUS0|Designator=6|PinPropagationDelay=0.000000E+000
|RECORD=2|OwnerIndex=28|OwnerPartId=1|Electrical=2|PinConglomerate=56|PinLength=20|Location.X=720|Location.Y=840|Name=RXD|Designator=10|PinPropagationDelay=0.000000E+000
|RECORD=2|OwnerIndex=28|OwnerPartId=1|Electrical=2|PinConglomerate=56|PinLength=20|Location.X=720|Location.Y=850|Name=TXD|Designator=7|PinPropagationDelay=0.000000E+000
|RECORD=2|OwnerIndex=28|OwnerPartId=1|Electrical=1|PinConglomerate=58|PinLength=20|Location.X=590|Location.Y=820|Name=USBDM|Designator=1|PinPropagationDelay=0.000000E+000
|RECORD=2|OwnerIndex=28|OwnerPartId=1|Electrical=1|PinConglomerate=58|PinLength=20|Location.X=590|Location.Y=810|Name=USBDP|Designator=12|PinPropagationDelay=0.000000E+000
|RECORD=2|OwnerIndex=28|OwnerPartId=1|Electrical=7|PinConglomerate=56|PinLength=20|Location.X=720|Location.Y=780|Name=GND|Designator=5|PinPropagationDelay=0.000000E+000
|RECORD=2|OwnerIndex=28|OwnerPartId=1|Electrical=7|PinConglomerate=56|PinLength=20|Location.X=720|Location.Y=770|Name=GND|Designator=13|PinPropagationDelay=0.000000E+000
|RECORD=41|OwnerIndex=28|IndexInSheet=14|OwnerPartId=-1|Location.X=568|Location.Y=860|Color=8388608|FontID=1|IsHidden=T|Text=3mm|Name=Length
|RECORD=41|OwnerIndex=28|IndexInSheet=15|OwnerPartId=-1|Location.X=568|Location.Y=860|Color=8388608|FontID=1|IsHidden=T|Text=2.97V|Name=Min Supply Voltage
|RECORD=41|OwnerIndex=28|IndexInSheet=16|OwnerPartId=-1|Location.X=568|Location.Y=860|Color=8388608|FontID=1|IsHidden=T|Text=DFN|Name=Case/Package
|RECORD=41|OwnerIndex=28|IndexInSheet=17|OwnerPartId=-1|Location.X=568|Location.Y=860|Color=8388608|FontID=1|IsHidden=T|Text=1|Name=Number of Ports
|RECORD=41|OwnerIndex=28|IndexInSheet=18|OwnerPartId=-1|Location.X=568|Location.Y=860|Color=8388608|FontID=1|IsHidden=T|Text=Surface Mount|Name=Mount
|RECORD=41|OwnerIndex=28|IndexInSheet=19|OwnerPartId=-1|Location.X=568|Location.Y=860|Color=8388608|FontID=1|IsHidden=T|Text=Tape and Reel|Name=Packaging
|RECORD=41|OwnerIndex=28|IndexInSheet=20|OwnerPartId=-1|Location.X=568|Location.Y=860|Color=8388608|FontID=1|IsHidden=T|Text=5V|Name=Operating Supply Voltage
|RECORD=41|OwnerIndex=28|IndexInSheet=21|OwnerPartId=-1|Location.X=568|Location.Y=860|Color=8388608|FontID=1|IsHidden=T|Text=85°C|Name=Max Operating Temperature
|RECORD=41|OwnerIndex=28|IndexInSheet=22|OwnerPartId=-1|Location.X=568|Location.Y=860|Color=8388608|FontID=1|IsHidden=T|Text=8mA|Name=Operating Supply Current
|RECORD=41|OwnerIndex=28|IndexInSheet=23|OwnerPartId=-1|Location.X=568|Location.Y=860|Color=8388608|FontID=1|IsHidden=T|Text=0.75mm|Name=Height
|RECORD=41|OwnerIndex=28|IndexInSheet=24|OwnerPartId=-1|Location.X=568|Location.Y=860|Color=8388608|FontID=1|IsHidden=T|Text=12|Name=Number of Pins
|RECORD=41|OwnerIndex=28|IndexInSheet=25|OwnerPartId=-1|Location.X=568|Location.Y=860|Color=8388608|FontID=1|IsHidden=T|Text=5.5V|Name=Max Supply Voltage
|RECORD=41|OwnerIndex=28|IndexInSheet=26|OwnerPartId=-1|Location.X=568|Location.Y=860|Color=8388608|FontID=1|IsHidden=T|Text=1|Name=Number of Transceivers
|RECORD=41|OwnerIndex=28|IndexInSheet=27|OwnerPartId=-1|Location.X=568|Location.Y=860|Color=8388608|FontID=1|IsHidden=T|Text=5000|Name=Package Quantity
|RECORD=41|OwnerIndex=28|IndexInSheet=28|OwnerPartId=-1|Location.X=568|Location.Y=860|Color=8388608|FontID=1|IsHidden=T|Text=3Mbps|Name=Data Rate
|RECORD=41|OwnerIndex=28|IndexInSheet=29|OwnerPartId=-1|Location.X=568|Location.Y=860|Color=8388608|FontID=1|IsHidden=T|Text=-40°C|Name=Min Operating Temperature
|RECORD=41|OwnerIndex=28|IndexInSheet=30|OwnerPartId=-1|Location.X=568|Location.Y=860|Color=8388608|FontID=1|IsHidden=T|Text=3mm|Name=Width
|RECORD=41|OwnerIndex=28|IndexInSheet=31|OwnerPartId=-1|Location.X=568|Location.Y=860|Color=8388608|FontID=1|IsHidden=T|Text=No SVHC|Name=REACH SVHC
|RECORD=41|OwnerIndex=28|IndexInSheet=32|OwnerPartId=-1|Location.X=568|Location.Y=860|Color=8388608|FontID=1|IsHidden=T|Text=UART|Name=Interface
|RECORD=41|OwnerIndex=28|IndexInSheet=33|OwnerPartId=-1|Location.X=568|Location.Y=860|Color=8388608|FontID=1|IsHidden=T|Text=Lead Free|Name=Lead Free
|RECORD=34|OwnerIndex=28|IndexInSheet=-1|OwnerPartId=-1|Location.X=590|Location.Y=860|Color=8388608|FontID=1|Text=U20|Name=Designator|ReadOnlyState=1
|RECORD=41|OwnerIndex=28|IndexInSheet=-1|OwnerPartId=1|Location.X=590|Location.Y=750|Color=8388608|FontID=1|Text=FT234XD-R|Name=Comment
|RECORD=44|OwnerIndex=28
|RECORD=45|OwnerIndex=78|IndexInSheet=-1|UseComponentLibrary=T|ModelName=FP-DFN-12-IPC_B|ModelType=PCBLIB|DatafileCount=1|ModelDatafileEntity0=FP-DFN-12-IPC_B|ModelDatafileKind0=PCBLib|IsCurrent=T|DatalinksLocked=T|DatabaseDatalinksLocked=T
|RECORD=46|OwnerIndex=79
|RECORD=48|OwnerIndex=79
|RECORD=45|OwnerIndex=78|IndexInSheet=-1|UseComponentLibrary=T|ModelName=FP-DFN-12-IPC_C|ModelType=PCBLIB|DatafileCount=1|ModelDatafileEntity0=FP-DFN-12-IPC_C|ModelDatafileKind0=PCBLib|DatalinksLocked=T|DatabaseDatalinksLocked=T
|RECORD=46|OwnerIndex=82
|RECORD=48|OwnerIndex=82
|RECORD=45|OwnerIndex=78|IndexInSheet=-1|UseComponentLibrary=T|ModelName=FP-DFN-12-IPC_A|ModelType=PCBLIB|DatafileCount=1|ModelDatafileEntity0=FP-DFN-12-IPC_A|ModelDatafileKind0=PCBLib|DatalinksLocked=T|DatabaseDatalinksLocked=T
|RECORD=46|OwnerIndex=85
|RECORD=48|OwnerIndex=85
|RECORD=45|OwnerIndex=78|IndexInSheet=-1|UseComponentLibrary=T|ModelName=FP-DFN-12-MFG|ModelType=PCBLIB|DatafileCount=1|ModelDatafileEntity0=FP-DFN-12-MFG|ModelDatafileKind0=PCBLib|DatalinksLocked=T|DatabaseDatalinksLocked=T
|RECORD=46|OwnerIndex=88
|RECORD=48|OwnerIndex=88
|RECORD=1|LibReference=11868f565c42a9108669ba33697ecf6|ComponentDescription=CAP CER 10000PF 50V X7R 0402|PartCount=2|DisplayModeCount=1|IndexInSheet=28|OwnerPartId=-1|Location.X=220|Location.Y=770|CurrentPartId=1|LibraryPath=*|SourceLibraryName=Altium Content Vault|TargetFileName=*|AreaColor=11599871|Color=128|PartIDLocked=T|DesignItemId=CMP-2100-03592-2|AllPinCount=2
|RECORD=2|OwnerIndex=91|OwnerPartId=1|Electrical=4|PinConglomerate=49|PinLength=7|Location.X=220|Location.Y=763|Name=1|Designator=1|PinPropagationDelay=0.000000E+000
|RECORD=2|OwnerIndex=91|OwnerPartId=1|Electrical=4|PinConglomerate=51|PinLength=6|Location.X=220|Location.Y=756|Name=2|Designator=2|PinPropagationDelay=0.000000E+000
|RECORD=13|OwnerIndex=91|IsNotAccesible=T|IndexInSheet=2|OwnerPartId=1|Location.X=230|Location.Y=763|Corner.X=210|Corner.Y=763|LineWidth=1|Color=16711680
|RECORD=13|OwnerIndex=91|IsNotAccesible=T|IndexInSheet=3|OwnerPartId=1|Location.X=230|Location.Y=757|Corner.X=210|Corner.Y=757|LineWidth=1|Color=16711680
|RECORD=13|OwnerIndex=91|IsNotAccesible=T|IndexInSheet=4|OwnerPartId=1|Location.X=220|Location.Y=763|Corner.X=220|Corner.Y=766|LineWidth=1|Color=16711680
|RECORD=13|OwnerIndex=91|IsNotAccesible=T|IndexInSheet=5|OwnerPartId=1|Location.X=220|Location.Y=756|Corner.X=220|Corner.Y=755|LineWidth=1|Color=16711680
|RECORD=41|OwnerIndex=91|IndexInSheet=6|OwnerPartId=-1|Location.X=209|Location.Y=772|Color=8388608|FontID=1|IsHidden=T|Text=Ceramic Capacitors|Name=Device Class L3
|RECORD=41|OwnerIndex=91|IndexInSheet=7|OwnerPartId=-1|Location.X=209|Location.Y=772|Color=8388608|FontID=1|IsHidden=T|Text=-55°C to +125°C|Name=Temperature
|RECORD=41|OwnerIndex=91|IndexInSheet=8|OwnerPartId=-1|Location.X=209|Location.Y=772|Color=8388608|FontID=3|IsHidden=T|Text=http://www.yageo.com/exep/pages/download/literatures/UPY-C_GEN_24.pdf|Name=Footprint Url
|RECORD=41|OwnerIndex=91|IndexInSheet=9|OwnerPartId=-1|Location.X=209|Location.Y=772|Color=8388608|FontID=1|IsHidden=T|Text=CAPC10050X50|Name=Ipc Land Pattern Name
|RECORD=41|OwnerIndex=91|IndexInSheet=10|OwnerPartId=-1|Location.X=209|Location.Y=772|Color=8388608|FontID=1|IsHidden=T|Text=Passive Components|Name=Device Class L1
|RECORD=41|OwnerIndex=91|IndexInSheet=11|OwnerPartId=-1|Location.X=209|Location.Y=772|Color=8388608|FontID=1|IsHidden=T|Text=No|Name=Automotive
|RECORD=41|OwnerIndex=91|IndexInSheet=12|OwnerPartId=-1|Location.X=209|Location.Y=772|Color=8388608|FontID=3|IsHidden=T|Text=https://octopart.com/cc0402krx7r9bb103-yageo-8376513|Name=Octopart
|RECORD=41|OwnerIndex=91|IndexInSheet=13|OwnerPartId=-1|Location.X=209|Location.Y=772|Color=8388608|FontID=1|IsHidden=T|Text=30ppm/°C|Name=Temperature Coefficient
|RECORD=41|OwnerIndex=91|IndexInSheet=14|OwnerPartId=-1|Location.X=209|Location.Y=772|Color=8388608|FontID=1|IsHidden=T|Text=CC0402KRX7R9BB103|Name=Manufacturer Part Number
|RECORD=41|OwnerIndex=91|IndexInSheet=15|OwnerPartId=-1|Location.X=209|Location.Y=772|Color=8388608|FontID=1|IsHidden=T|Text=Yes|Name=Lead Free
|RECORD=41|OwnerIndex=91|IndexInSheet=16|OwnerPartId=-1|Location.X=209|Location.Y=772|Color=8388608|FontID=1|IsHidden=T|Text=-55°C|Name=Temperature Range Low
|RECORD=41|OwnerIndex=91|IndexInSheet=17|OwnerPartId=-1|Location.X=209|Location.Y=772|Color=8388608|FontID=1|IsHidden=T|Text=0.55mm|Name=Height
|RECORD=41|OwnerIndex=91|IndexInSheet=18|OwnerPartId=-1|Location.X=209|Location.Y=772|Color=8388608|FontID=3|IsHidden=T|Text=http://www.yageo.com/documents/recent/UPY-GP_NP0_16V-to-50V_16.pdf|Name=ComponentLink2URL
|RECORD=41|OwnerIndex=91|IndexInSheet=19|OwnerPartId=-1|Location.X=209|Location.Y=772|Color=8388608|FontID=1|IsHidden=T|Text=10 nF|Name=Capacitance
|RECORD=41|OwnerIndex=91|IndexInSheet=20|OwnerPartId=-1|Location.X=209|Location.Y=772|Color=8388608|FontID=1|IsHidden=T|Text=Cap|Name=Category
|RECORD=41|OwnerIndex=91|IndexInSheet=21|OwnerPartId=-1|Location.X=209|Location.Y=772|Color=8388608|FontID=1|IsHidden=T|Text=Ceramic|Name=Material
|RECORD=41|OwnerIndex=91|IndexInSheet=22|OwnerPartId=-1|Location.X=209|Location.Y=772|Color=8388608|FontID=1|IsHidden=T|Text=YAGEO|Name=Manufacturer
|RECORD=41|OwnerIndex=91|IndexInSheet=23|OwnerPartId=-1|Location.X=209|Location.Y=772|Color=8388608|FontID=1|IsHidden=T|Text=Datasheet|Name=ComponentLink2Description
|RECORD=41|OwnerIndex=91|IndexInSheet=24|OwnerPartId=-1|Location.X=209|Location.Y=772|Color=8388608|FontID=1|IsHidden=T|Text=+125°C|Name=Temperature Range High
|RECORD=41|OwnerIndex=91|IndexInSheet=25|OwnerPartId=-1|Location.X=209|Location.Y=772|Color=8388608|FontID=1|IsHidden=T|Text=CAP CER 10000PF 50V X7R 0402|Name=Digikey Description
|RECORD=41|OwnerIndex=91|IndexInSheet=26|OwnerPartId=-1|Location.X=209|Location.Y=772|Color=8388608|FontID=1|IsHidden=T|Text=50 V|Name=Voltage Rating
|RECORD=41|OwnerIndex=91|IndexInSheet=27|OwnerPartId=-1|Location.X=209|Location.Y=772|Color=8388608|FontID=1|IsHidden=T|Text=NA|Name=Automotive Grade
|RECORD=41|OwnerIndex=91|IndexInSheet=28|OwnerPartId=-1|Location.X=209|Location.Y=772|Color=8388608|FontID=1|IsHidden=T|Text=CC0402|Name=Package
|RECORD=41|OwnerIndex=91|IndexInSheet=29|OwnerPartId=-1|Location.X=209|Location.Y=772|Color=8388608|FontID=1|IsHidden=T|Text=Capacitors|Name=Device Class L2
|RECORD=41|OwnerIndex=91|IndexInSheet=30|OwnerPartId=-1|Location.X=209|Location.Y=772|Color=8388608|FontID=1|IsHidden=T|Text=0402 10 nF 50 V ±10 % Tolerance X7R SMT Multilayer Ceramic Capacitor|Name=Mouser Description
|RECORD=41|OwnerIndex=91|IndexInSheet=31|OwnerPartId=-1|Location.X=209|Location.Y=772|Color=8388608|FontID=1|IsHidden=T|Text=0.1|Name=Tolerance
|RECORD=41|OwnerIndex=91|IndexInSheet=32|OwnerPartId=-1|Location.X=209|Location.Y=772|Color=8388608|FontID=1|IsHidden=T|Text=10 nF|Name=Value
|RECORD=41|OwnerIndex=91|IndexInSheet=33|OwnerPartId=-1|Location.X=209|Location.Y=772|Color=8388608|FontID=1|IsHidden=T|Text=TRUE|Name=RoHS
|RECORD=41|OwnerIndex=91|IndexInSheet=34|OwnerPartId=-1|Location.X=209|Location.Y=772|Color=8388608|FontID=1|IsHidden=T|Text=X7R|Name=Temperature Characteristic
|RECORD=34|OwnerIndex=91|IndexInSheet=-1|OwnerPartId=-1|Location.X=210|Location.Y=750|Orientation=1|Color=8388608|FontID=2|Text=C86|Name=Designator|ReadOnlyState=1
|RECORD=41|OwnerIndex=91|IndexInSheet=-1|OwnerPartId=1|Location.X=240|Location.Y=730|Orientation=1|Color=8388608|FontID=2|Text=10nF_50V_0402|Name=Comment
|RECORD=44|OwnerIndex=91
|RECORD=45|OwnerIndex=131|IndexInSheet=-1|UseComponentLibrary=T|ModelName=FP-CC0402-MFG|ModelType=PCBLIB|DatafileCount=1|ModelDatafileEntity0=FP-CC0402-MFG|ModelDatafileKind0=PCBLib|IsCurrent=T|DatalinksLocked=T|DatabaseDatalinksLocked=T
|RECORD=46|OwnerIndex=132
|RECORD=48|OwnerIndex=132
|RECORD=45|OwnerIndex=131|IndexInSheet=-1|UseComponentLibrary=T|ModelName=FP-CC0402-IPC_C|ModelType=PCBLIB|DatafileCount=1|ModelDatafileEntity0=FP-CC0402-IPC_C|ModelDatafileKind0=PCBLib|DatalinksLocked=T|DatabaseDatalinksLocked=T
|RECORD=46|OwnerIndex=135
|RECORD=48|OwnerIndex=135
|RECORD=45|OwnerIndex=131|IndexInSheet=-1|UseComponentLibrary=T|ModelName=FP-CC0402-IPC_B|ModelType=PCBLIB|DatafileCount=1|ModelDatafileEntity0=FP-CC0402-IPC_B|ModelDatafileKind0=PCBLib|DatalinksLocked=T|DatabaseDatalinksLocked=T
|RECORD=46|OwnerIndex=138
|RECORD=48|OwnerIndex=138
|RECORD=45|OwnerIndex=131|IndexInSheet=-1|UseComponentLibrary=T|ModelName=FP-CC0402-IPC_A|ModelType=PCBLIB|DatafileCount=1|ModelDatafileEntity0=FP-CC0402-IPC_A|ModelDatafileKind0=PCBLib|DatalinksLocked=T|DatabaseDatalinksLocked=T
|RECORD=46|OwnerIndex=141
|RECORD=48|OwnerIndex=141
|RECORD=1|LibReference=5f30dd21d616792df468990f7003faa|ComponentDescription=Chip Ferrite Bead, 0603, 600O @ 100MHz, 0.15O, 25%, 1.3A|PartCount=2|DisplayModeCount=1|IndexInSheet=29|OwnerPartId=-1|Location.X=250|Location.Y=850|CurrentPartId=1|LibraryPath=*|SourceLibraryName=Altium Content Vault|TargetFileName=*|AreaColor=11599871|Color=128|PartIDLocked=T|DesignItemId=CMP-0686-00581-3|AllPinCount=2
|RECORD=2|OwnerIndex=144|OwnerPartId=1|Electrical=4|PinConglomerate=50|PinLength=20|Location.X=270|Location.Y=850|Name=1|Designator=1|PinPropagationDelay=0.000000E+000
|RECORD=2|OwnerIndex=144|OwnerPartId=1|Electrical=4|PinConglomerate=48|PinLength=20|Location.X=280|Location.Y=850|Name=2|Designator=2|PinPropagationDelay=0.000000E+000
|RECORD=13|OwnerIndex=144|IsNotAccesible=T|IndexInSheet=2|OwnerPartId=1|Location.X=267|Location.Y=847|Corner.X=278|Corner.Y=858|LineWidth=1|Color=16711680
|RECORD=13|OwnerIndex=144|IsNotAccesible=T|IndexInSheet=3|OwnerPartId=1|Location.X=272|Location.Y=842|Corner.X=283|Corner.Y=853|LineWidth=1|Color=16711680
|RECORD=13|OwnerIndex=144|IsNotAccesible=T|IndexInSheet=4|OwnerPartId=1|Location.X=278|Location.Y=858|Corner.X=283|Corner.Y=853|LineWidth=1|Color=16711680
|RECORD=13|OwnerIndex=144|IsNotAccesible=T|IndexInSheet=5|OwnerPartId=1|Location.X=272|Location.Y=842|Corner.X=267|Corner.Y=847|LineWidth=1|Color=16711680
|RECORD=13|OwnerIndex=144|IsNotAccesible=T|IndexInSheet=6|OwnerPartId=1|Location.X=270|Location.Y=850|Corner.X=267|Corner.Y=850|LineWidth=1|Color=16711680
|RECORD=13|OwnerIndex=144|IsNotAccesible=T|IndexInSheet=7|OwnerPartId=1|Location.X=280|Location.Y=850|Corner.X=283|Corner.Y=850|LineWidth=1|Color=16711680
|RECORD=41|OwnerIndex=144|IndexInSheet=8|OwnerPartId=-1|Location.X=248|Location.Y=859|Color=8388608|FontID=1|IsHidden=T|Text=Steel|Name=Material
|RECORD=41|OwnerIndex=144|IndexInSheet=9|OwnerPartId=-1|Location.X=248|Location.Y=859|Color=8388608|FontID=1|IsHidden=T|Text=25%|Name=Tolerance
|RECORD=41|OwnerIndex=144|IndexInSheet=10|OwnerPartId=-1|Location.X=248|Location.Y=859|Color=8388608|FontID=1|IsHidden=T|Text=1608|Name=Case Code (Metric)
|RECORD=41|OwnerIndex=144|IndexInSheet=11|OwnerPartId=-1|Location.X=248|Location.Y=859|Color=8388608|FontID=1|IsHidden=T|Text=0.8mm|Name=Width
|RECORD=41|OwnerIndex=144|IndexInSheet=12|OwnerPartId=-1|Location.X=248|Location.Y=859|Color=8388608|FontID=1|IsHidden=T|Text=1.3A|Name=DC Current
|RECORD=41|OwnerIndex=144|IndexInSheet=13|OwnerPartId=-1|Location.X=248|Location.Y=859|Color=8388608|FontID=1|IsHidden=T|Text=1.3A|Name=Max DC Current
|RECORD=41|OwnerIndex=144|IndexInSheet=14|OwnerPartId=-1|Location.X=248|Location.Y=859|Color=8388608|FontID=1|IsHidden=T|Text=1|Name=Package Quantity
|RECORD=41|OwnerIndex=144|IndexInSheet=15|OwnerPartId=-1|Location.X=248|Location.Y=859|Color=8388608|FontID=1|IsHidden=T|Text=1|Name=Number of Lines
|RECORD=41|OwnerIndex=144|IndexInSheet=16|OwnerPartId=-1|Location.X=248|Location.Y=859|Color=8388608|FontID=1|IsHidden=T|Text=2|Name=Number of Pins
|RECORD=41|OwnerIndex=144|IndexInSheet=17|OwnerPartId=-1|Location.X=248|Location.Y=859|Color=8388608|FontID=1|IsHidden=T|Text=Not|Name=Military Standard
|RECORD=41|OwnerIndex=144|IndexInSheet=18|OwnerPartId=-1|Location.X=248|Location.Y=859|Color=8388608|FontID=1|IsHidden=T|Text=Yes|Name=RoHS Compliant
|RECORD=41|OwnerIndex=144|IndexInSheet=19|OwnerPartId=-1|Location.X=248|Location.Y=859|Color=8388608|FontID=1|IsHidden=T|Text=SMD/SMT|Name=Termination
|RECORD=41|OwnerIndex=144|IndexInSheet=20|OwnerPartId=-1|Location.X=248|Location.Y=859|Color=8388608|FontID=1|IsHidden=T|Text=600R|Name=Impedance
|RECORD=41|OwnerIndex=144|IndexInSheet=21|OwnerPartId=-1|Location.X=248|Location.Y=859|Color=8388608|FontID=1|IsHidden=T|Text=125°C|Name=Max Operating Temperature
|RECORD=41|OwnerIndex=144|IndexInSheet=22|OwnerPartId=-1|Location.X=248|Location.Y=859|Color=8388608|FontID=1|IsHidden=T|Text=1.6mm|Name=Length
|RECORD=41|OwnerIndex=144|IndexInSheet=23|OwnerPartId=-1|Location.X=248|Location.Y=859|Color=8388608|FontID=1|IsHidden=T|Text=0.8mm|Name=Depth
|RECORD=41|OwnerIndex=144|IndexInSheet=24|OwnerPartId=-1|Location.X=248|Location.Y=859|Color=8388608|FontID=1|IsHidden=T|Text=0603|Name=Case Code (Imperial)
|RECORD=41|OwnerIndex=144|IndexInSheet=25|OwnerPartId=-1|Location.X=248|Location.Y=859|Color=8388608|FontID=1|IsHidden=T|Text=BLM18K|Name=Series
|RECORD=41|OwnerIndex=144|IndexInSheet=26|OwnerPartId=-1|Location.X=248|Location.Y=859|Color=8388608|FontID=1|IsHidden=T|Text=FERRITE BEAD|Name=Inductor Type
|RECORD=41|OwnerIndex=144|IndexInSheet=27|OwnerPartId=-1|Location.X=248|Location.Y=859|Color=8388608|FontID=1|IsHidden=T|Text=150mR|Name=DC Resistance (DCR)
|RECORD=41|OwnerIndex=144|IndexInSheet=28|OwnerPartId=-1|Location.X=248|Location.Y=859|Color=8388608|FontID=1|IsHidden=T|Text=Ferrite|Name=Core Material
|RECORD=41|OwnerIndex=144|IndexInSheet=29|OwnerPartId=-1|Location.X=248|Location.Y=859|Color=8388608|FontID=1|IsHidden=T|Text=1|Name=Number of Circuits
|RECORD=41|OwnerIndex=144|IndexInSheet=30|OwnerPartId=-1|Location.X=248|Location.Y=859|Color=8388608|FontID=1|IsHidden=T|Text=0.8mm|Name=Height
|RECORD=41|OwnerIndex=144|IndexInSheet=31|OwnerPartId=-1|Location.X=248|Location.Y=859|Color=8388608|FontID=1|IsHidden=T|Text=0603|Name=Case/Package
|RECORD=41|OwnerIndex=144|IndexInSheet=32|OwnerPartId=-1|Location.X=248|Location.Y=859|Color=8388608|FontID=1|IsHidden=T|Text=No SVHC|Name=REACH SVHC
|RECORD=41|OwnerIndex=144|IndexInSheet=33|OwnerPartId=-1|Location.X=248|Location.Y=859|Color=8388608|FontID=1|IsHidden=T|Text=Tape and Reel|Name=Packaging
|RECORD=41|OwnerIndex=144|IndexInSheet=34|OwnerPartId=-1|Location.X=248|Location.Y=859|Color=8388608|FontID=1|IsHidden=T|Text=-55°C|Name=Min Operating Temperature
|RECORD=41|OwnerIndex=144|IndexInSheet=35|OwnerPartId=-1|Location.X=248|Location.Y=859|Color=8388608|FontID=1|IsHidden=T|Text=1.3A|Name=Max Current Rating
|RECORD=41|OwnerIndex=144|IndexInSheet=36|OwnerPartId=-1|Location.X=248|Location.Y=859|Color=8388608|FontID=1|IsHidden=T|Text=No|Name=Radiation Hardening
|RECORD=41|OwnerIndex=144|IndexInSheet=37|OwnerPartId=-1|Location.X=248|Location.Y=859|Color=8388608|FontID=1|IsHidden=T|Text=1.3A|Name=Current Rating
|RECORD=41|OwnerIndex=144|IndexInSheet=38|OwnerPartId=-1|Location.X=248|Location.Y=859|Color=8388608|FontID=1|IsHidden=T|Text=Lead Free|Name=Lead Free
|RECORD=41|OwnerIndex=144|IndexInSheet=39|OwnerPartId=-1|Location.X=248|Location.Y=859|Color=8388608|FontID=1|IsHidden=T|Text=100MHz|Name=Test Frequency
|RECORD=41|OwnerIndex=144|IndexInSheet=40|OwnerPartId=-1|Location.X=248|Location.Y=859|Color=8388608|FontID=1|IsHidden=T|Text=7.1E-05oz|Name=Weight
|RECORD=34|OwnerIndex=144|IndexInSheet=-1|OwnerPartId=-1|Location.X=266|Location.Y=859|Color=8388608|FontID=1|Text=FB1|Name=Designator|ReadOnlyState=1
|RECORD=41|OwnerIndex=144|IndexInSheet=-1|OwnerPartId=1|Location.X=266|Location.Y=831|Color=8388608|FontID=1|Text=600ohm_1.3A_0603|Name=Comment
|RECORD=44|OwnerIndex=144
|RECORD=45|OwnerIndex=190|IndexInSheet=-1|UseComponentLibrary=T|ModelName=FP-BLM18-0_15-t0_8-IPC_A|ModelType=PCBLIB|DatafileCount=1|ModelDatafileEntity0=FP-BLM18-0_15-t0_8-IPC_A|ModelDatafileKind0=PCBLib|IsCurrent=T|DatalinksLocked=T|DatabaseDatalinksLocked=T
|RECORD=46|OwnerIndex=191
|RECORD=48|OwnerIndex=191
|RECORD=45|OwnerIndex=190|IndexInSheet=-1|UseComponentLibrary=T|ModelName=FP-BLM18-0_15-t0_8-MFG|ModelType=PCBLIB|DatafileCount=1|ModelDatafileEntity0=FP-BLM18-0_15-t0_8-MFG|ModelDatafileKind0=PCBLib|DatalinksLocked=T|DatabaseDatalinksLocked=T
|RECORD=46|OwnerIndex=194
|RECORD=48|OwnerIndex=194
|RECORD=45|OwnerIndex=190|IndexInSheet=-1|UseComponentLibrary=T|ModelName=FP-BLM18-0_15-t0_8-IPC_B|ModelType=PCBLIB|DatafileCount=1|ModelDatafileEntity0=FP-BLM18-0_15-t0_8-IPC_B|ModelDatafileKind0=PCBLib|DatalinksLocked=T|DatabaseDatalinksLocked=T
|RECORD=46|OwnerIndex=197
|RECORD=48|OwnerIndex=197
|RECORD=45|OwnerIndex=190|IndexInSheet=-1|UseComponentLibrary=T|ModelName=FP-BLM18-0_15-t0_8-IPC_C|ModelType=PCBLIB|DatafileCount=1|ModelDatafileEntity0=FP-BLM18-0_15-t0_8-IPC_C|ModelDatafileKind0=PCBLib|DatalinksLocked=T|DatabaseDatalinksLocked=T
|RECORD=46|OwnerIndex=200
|RECORD=48|OwnerIndex=200
|RECORD=17|IndexInSheet=30|OwnerPartId=-1|Style=4|ShowNetName=T|Location.X=180|Location.Y=690|Orientation=3|Color=128|FontID=1|Text=GND
|RECORD=25|IndexInSheet=31|OwnerPartId=-1|Location.X=170|Location.Y=830|Color=128|FontID=1|Text=FTDI_USB_R_N
|RECORD=25|IndexInSheet=32|OwnerPartId=-1|Location.X=170|Location.Y=810|Color=128|FontID=1|Text=FTDI_USB_R_P
|RECORD=1|LibReference=b4654b650e69147ec39a6b967a45e02|ComponentDescription=General Purpose Ceramic Capacitor, 0402, 100nF, 10%, X7R, 15%, 25V|PartCount=2|DisplayModeCount=1|IndexInSheet=33|OwnerPartId=-1|Location.X=550|Location.Y=720|CurrentPartId=1|LibraryPath=*|SourceLibraryName=Altium Content Vault|TargetFileName=*|AreaColor=11599871|Color=128|PartIDLocked=T|DesignItemId=CMP-2008-02519-2|AllPinCount=2
|RECORD=2|OwnerIndex=206|OwnerPartId=1|Electrical=4|PinConglomerate=49|PinLength=7|Location.X=550|Location.Y=713|Name=1|Designator=1|PinPropagationDelay=0.000000E+000
|RECORD=2|OwnerIndex=206|OwnerPartId=1|Electrical=4|PinConglomerate=51|PinLength=6|Location.X=550|Location.Y=706|Name=2|Designator=2|PinPropagationDelay=0.000000E+000
|RECORD=13|OwnerIndex=206|IsNotAccesible=T|IndexInSheet=2|OwnerPartId=1|Location.X=560|Location.Y=713|Corner.X=540|Corner.Y=713|LineWidth=1|Color=16711680
|RECORD=13|OwnerIndex=206|IsNotAccesible=T|IndexInSheet=3|OwnerPartId=1|Location.X=560|Location.Y=707|Corner.X=540|Corner.Y=707|LineWidth=1|Color=16711680
|RECORD=13|OwnerIndex=206|IsNotAccesible=T|IndexInSheet=4|OwnerPartId=1|Location.X=550|Location.Y=713|Corner.X=550|Corner.Y=716|LineWidth=1|Color=16711680
|RECORD=13|OwnerIndex=206|IsNotAccesible=T|IndexInSheet=5|OwnerPartId=1|Location.X=550|Location.Y=706|Corner.X=550|Corner.Y=705|LineWidth=1|Color=16711680
|RECORD=41|OwnerIndex=206|IndexInSheet=6|OwnerPartId=-1|Location.X=539|Location.Y=722|Color=8388608|FontID=1|IsHidden=T|Text=1|Name=Package Quantity
|RECORD=41|OwnerIndex=206|IndexInSheet=7|OwnerPartId=-1|Location.X=539|Location.Y=722|Color=8388608|FontID=1|IsHidden=T|Text=100nF|Name=Capacitance
|RECORD=41|OwnerIndex=206|IndexInSheet=8|OwnerPartId=-1|Location.X=539|Location.Y=722|Color=8388608|FontID=1|IsHidden=T|Text=-55°C|Name=Min Operating Temperature
|RECORD=41|OwnerIndex=206|IndexInSheet=9|OwnerPartId=-1|Location.X=539|Location.Y=722|Color=8388608|FontID=1|IsHidden=T|Text=25V|Name=Voltage
|RECORD=41|OwnerIndex=206|IndexInSheet=10|OwnerPartId=-1|Location.X=539|Location.Y=722|Color=8388608|FontID=1|IsHidden=T|Text=25V|Name=Voltage Rating
|RECORD=41|OwnerIndex=206|IndexInSheet=11|OwnerPartId=-1|Location.X=539|Location.Y=722|Color=8388608|FontID=1|IsHidden=T|Text=Flat|Name=Construction
|RECORD=41|OwnerIndex=206|IndexInSheet=12|OwnerPartId=-1|Location.X=539|Location.Y=722|Color=8388608|FontID=1|IsHidden=T|Text=125°C|Name=Max Operating Temperature
|RECORD=41|OwnerIndex=206|IndexInSheet=13|OwnerPartId=-1|Location.X=539|Location.Y=722|Color=8388608|FontID=1|IsHidden=T|Text=No|Name=Radiation Hardening
|RECORD=41|OwnerIndex=206|IndexInSheet=14|OwnerPartId=-1|Location.X=539|Location.Y=722|Color=8388608|FontID=1|IsHidden=T|Text=0.5mm|Name=Depth
|RECORD=41|OwnerIndex=206|IndexInSheet=15|OwnerPartId=-1|Location.X=539|Location.Y=722|Color=8388608|FontID=1|IsHidden=T|Text=0.022inch|Name=Thickness
|RECORD=41|OwnerIndex=206|IndexInSheet=16|OwnerPartId=-1|Location.X=539|Location.Y=722|Color=8388608|FontID=1|IsHidden=T|Text=25V|Name=Voltage Rating (DC)
|RECORD=41|OwnerIndex=206|IndexInSheet=17|OwnerPartId=-1|Location.X=539|Location.Y=722|Color=8388608|FontID=1|IsHidden=T|Text=2|Name=Number of Pins
|RECORD=41|OwnerIndex=206|IndexInSheet=18|OwnerPartId=-1|Location.X=539|Location.Y=722|Color=8388608|FontID=1|IsHidden=T|Text=Lead Free|Name=Lead Free
|RECORD=41|OwnerIndex=206|IndexInSheet=19|OwnerPartId=-1|Location.X=539|Location.Y=722|Color=8388608|FontID=1|IsHidden=T|Text=-|Name=Series
|RECORD=41|OwnerIndex=206|IndexInSheet=20|OwnerPartId=-1|Location.X=539|Location.Y=722|Color=8388608|FontID=1|IsHidden=T|Text=No SVHC|Name=REACH SVHC
|RECORD=41|OwnerIndex=206|IndexInSheet=21|OwnerPartId=-1|Location.X=539|Location.Y=722|Color=8388608|FontID=1|IsHidden=T|Text=1mm|Name=Length
|RECORD=41|OwnerIndex=206|IndexInSheet=22|OwnerPartId=-1|Location.X=539|Location.Y=722|Color=8388608|FontID=1|IsHidden=T|Text=X7R|Name=Dielectric
|RECORD=41|OwnerIndex=206|IndexInSheet=23|OwnerPartId=-1|Location.X=539|Location.Y=722|Color=8388608|FontID=1|IsHidden=T|Text=Yes|Name=RoHS Compliant
|RECORD=41|OwnerIndex=206|IndexInSheet=24|OwnerPartId=-1|Location.X=539|Location.Y=722|Color=8388608|FontID=1|IsHidden=T|Text=Surface Mount|Name=Mount
|RECORD=41|OwnerIndex=206|IndexInSheet=25|OwnerPartId=-1|Location.X=539|Location.Y=722|Color=8388608|FontID=1|IsHidden=T|Text=Tape and Reel|Name=Packaging
|RECORD=41|OwnerIndex=206|IndexInSheet=26|OwnerPartId=-1|Location.X=539|Location.Y=722|Color=8388608|FontID=1|IsHidden=T|Text=0402|Name=Case/Package
|RECORD=41|OwnerIndex=206|IndexInSheet=27|OwnerPartId=-1|Location.X=539|Location.Y=722|Color=8388608|FontID=1|IsHidden=T|Text=0402|Name=Case Code (Imperial)
|RECORD=41|OwnerIndex=206|IndexInSheet=28|OwnerPartId=-1|Location.X=539|Location.Y=722|Color=8388608|FontID=1|IsHidden=T|Text=SMD/SMT|Name=Termination
|RECORD=41|OwnerIndex=206|IndexInSheet=29|OwnerPartId=-1|Location.X=539|Location.Y=722|Color=8388608|FontID=1|IsHidden=T|Text=0.02inch|Name=Width
|RECORD=41|OwnerIndex=206|IndexInSheet=30|OwnerPartId=-1|Location.X=539|Location.Y=722|Color=8388608|FontID=1|IsHidden=T|Text=1005|Name=Case Code (Metric)
|RECORD=41|OwnerIndex=206|IndexInSheet=31|OwnerPartId=-1|Location.X=539|Location.Y=722|Color=8388608|FontID=1|IsHidden=T|Text=10%|Name=Tolerance
|RECORD=34|OwnerIndex=206|IndexInSheet=-1|OwnerPartId=-1|Location.X=540|Location.Y=700|Orientation=1|Color=8388608|FontID=2|Text=C92|Name=Designator|ReadOnlyState=1
|RECORD=41|OwnerIndex=206|IndexInSheet=-1|OwnerPartId=1|Location.X=570|Location.Y=685|Orientation=1|Color=8388608|FontID=2|Text=0.1uF_25V_0402|Name=Comment
|RECORD=44|OwnerIndex=206
|RECORD=45|OwnerIndex=243|IndexInSheet=-1|UseComponentLibrary=T|ModelName=FP-0402-L_1_0_1-W_0_5_0_1-IPC_C|ModelType=PCBLIB|DatafileCount=1|ModelDatafileEntity0=FP-0402-L_1_0_1-W_0_5_0_1-IPC_C|ModelDatafileKind0=PCBLib|IsCurrent=T|DatalinksLocked=T|DatabaseDatalinksLocked=T
|RECORD=46|OwnerIndex=244
|RECORD=48|OwnerIndex=244
|RECORD=45|OwnerIndex=243|IndexInSheet=-1|UseComponentLibrary=T|ModelName=FP-0402-L_1_0_1-W_0_5_0_1-IPC_B|ModelType=PCBLIB|DatafileCount=1|ModelDatafileEntity0=FP-0402-L_1_0_1-W_0_5_0_1-IPC_B|ModelDatafileKind0=PCBLib|DatalinksLocked=T|DatabaseDatalinksLocked=T
|RECORD=46|OwnerIndex=247
|RECORD=48|OwnerIndex=247
|RECORD=45|OwnerIndex=243|IndexInSheet=-1|UseComponentLibrary=T|ModelName=FP-0402-L_1_0_1-W_0_5_0_1-MFG|ModelType=PCBLIB|DatafileCount=1|ModelDatafileEntity0=FP-0402-L_1_0_1-W_0_5_0_1-MFG|ModelDatafileKind0=PCBLib|DatalinksLocked=T|DatabaseDatalinksLocked=T
|RECORD=46|OwnerIndex=250
|RECORD=48|OwnerIndex=250
|RECORD=45|OwnerIndex=243|IndexInSheet=-1|UseComponentLibrary=T|ModelName=FP-0402-L_1_0_1-W_0_5_0_1-IPC_A|ModelType=PCBLIB|DatafileCount=1|ModelDatafileEntity0=FP-0402-L_1_0_1-W_0_5_0_1-IPC_A|ModelDatafileKind0=PCBLib|DatalinksLocked=T|DatabaseDatalinksLocked=T
|RECORD=46|OwnerIndex=253
|RECORD=48|OwnerIndex=253
|RECORD=1|LibReference=RES|PartCount=2|DisplayModeCount=2|IndexInSheet=34|OwnerPartId=-1|Location.X=430|Location.Y=820|CurrentPartId=1|SourceLibraryName=Altium Content Vault|TargetFileName=*|AreaColor=11599871|Color=128|PartIDLocked=F|DesignItemId=CMP-2002-08434-1|AllPinCount=2
|RECORD=2|OwnerIndex=256|OwnerPartId=1|OwnerPartDisplayMode=1|FormalType=1|Electrical=4|PinConglomerate=32|PinLength=10|Location.X=450|Location.Y=810|Name=2|Designator=2|PinPropagationDelay=0.000000E+000
|RECORD=2|OwnerIndex=256|OwnerPartId=1|OwnerPartDisplayMode=1|FormalType=1|Electrical=4|PinConglomerate=34|PinLength=10|Location.X=430|Location.Y=810|Name=1|Designator=1|PinPropagationDelay=0.000000E+000
|RECORD=14|OwnerIndex=256|IsNotAccesible=T|IndexInSheet=2|OwnerPartId=1|OwnerPartDisplayMode=1|Location.X=430|Location.Y=806|Corner.X=450|Corner.Y=814|LineWidth=1|Color=16711680|AreaColor=11599871
|RECORD=2|OwnerIndex=256|OwnerPartId=1|FormalType=1|Electrical=4|PinConglomerate=32|PinLength=10|Location.X=450|Location.Y=810|Name=2|Designator=2|PinPropagationDelay=0.000000E+000
|RECORD=2|OwnerIndex=256|OwnerPartId=1|FormalType=1|Electrical=4|PinConglomerate=34|PinLength=10|Location.X=430|Location.Y=810|Name=1|Designator=1|PinPropagationDelay=0.000000E+000
|RECORD=6|OwnerIndex=256|IsNotAccesible=T|IndexInSheet=5|OwnerPartId=1|LineWidth=1|Color=16711680|LocationCount=10|X1=450|Y1=810|X2=446|Y2=810|X3=445|Y3=808|X4=443|Y4=812|X5=441|Y5=808|X6=439|Y6=812|X7=437|Y7=808|X8=435|Y8=812|X9=434|Y9=810|X10=430|Y10=810
|RECORD=41|OwnerIndex=256|IndexInSheet=6|OwnerPartId=-1|Location.X=418|Location.Y=823|Color=8388608|FontID=1|IsHidden=T|Text=CRCW040227R0FKED|Name=Part Number
|RECORD=41|OwnerIndex=256|IndexInSheet=7|OwnerPartId=-1|Location.X=418|Location.Y=823|Color=8388608|FontID=1|IsHidden=T|Text=Vishay Dale|Name=Manufacturer
|RECORD=34|OwnerIndex=256|IndexInSheet=-1|OwnerPartId=-1|Location.X=410|Location.Y=810|Color=8388608|FontID=1|Text=R81|Name=Designator|ReadOnlyState=1
|RECORD=41|OwnerIndex=256|IndexInSheet=-1|OwnerPartId=-1|Location.X=430|Location.Y=810|Color=8388608|FontID=1|Text=27_1%_0402|Name=Comment
|RECORD=44|OwnerIndex=256
|RECORD=45|OwnerIndex=271|IndexInSheet=-1|Description=Chip Resistor, 2-Leads, Body 1.00x0.50mm, IPC Medium Density|UseComponentLibrary=T|ModelName=RESC1005X40X25NL05T05|ModelType=PCBLIB|DatafileCount=1|ModelDatafileEntity0=RESC1005X40X25NL05T05|ModelDatafileKind0=PCBLib|IsCurrent=T|DatalinksLocked=T|DatabaseDatalinksLocked=T
|RECORD=46|OwnerIndex=272
|RECORD=48|OwnerIndex=272
|RECORD=41|OwnerIndex=274|IndexInSheet=-1|OwnerPartId=-1|Color=8388608|FontID=1|IsHidden=T|Text=2D|Name=Available Preview Images
|RECORD=45|OwnerIndex=271|IndexInSheet=-1|Description=Chip Resistor, 2-Leads, Body 1.00x0.50mm, IPC High Density|UseComponentLibrary=T|ModelName=RESC1005X40X25LL05T05|ModelType=PCBLIB|DatafileCount=1|ModelDatafileEntity0=RESC1005X40X25LL05T05|ModelDatafileKind0=PCBLib|DatalinksLocked=T|DatabaseDatalinksLocked=T
|RECORD=46|OwnerIndex=276
|RECORD=48|OwnerIndex=276
|RECORD=41|OwnerIndex=278|IndexInSheet=-1|OwnerPartId=-1|Color=8388608|FontID=1|IsHidden=T|Text=2D|Name=Available Preview Images
|RECORD=45|OwnerIndex=271|IndexInSheet=-1|Description=Chip Resistor, 2-Leads, Body 1.00x0.50mm, IPC Low Density|UseComponentLibrary=T|ModelName=RESC1005X40X25ML05T05|ModelType=PCBLIB|DatafileCount=1|ModelDatafileEntity0=RESC1005X40X25ML05T05|ModelDatafileKind0=PCBLib|DatalinksLocked=T|DatabaseDatalinksLocked=T
|RECORD=46|OwnerIndex=280
|RECORD=48|OwnerIndex=280
|RECORD=41|OwnerIndex=282|IndexInSheet=-1|OwnerPartId=-1|Color=8388608|FontID=1|IsHidden=T|Text=2D|Name=Available Preview Images
|RECORD=1|LibReference=RES|PartCount=2|DisplayModeCount=2|IndexInSheet=35|OwnerPartId=-1|Location.X=430|Location.Y=830|CurrentPartId=1|SourceLibraryName=Altium Content Vault|TargetFileName=*|AreaColor=11599871|Color=128|PartIDLocked=F|DesignItemId=CMP-2002-08434-1|AllPinCount=2
|RECORD=2|OwnerIndex=284|OwnerPartId=1|OwnerPartDisplayMode=1|FormalType=1|Electrical=4|PinConglomerate=32|PinLength=10|Location.X=450|Location.Y=820|Name=2|Designator=2|PinPropagationDelay=0.000000E+000
|RECORD=2|OwnerIndex=284|OwnerPartId=1|OwnerPartDisplayMode=1|FormalType=1|Electrical=4|PinConglomerate=34|PinLength=10|Location.X=430|Location.Y=820|Name=1|Designator=1|PinPropagationDelay=0.000000E+000
|RECORD=14|OwnerIndex=284|IsNotAccesible=T|IndexInSheet=2|OwnerPartId=1|OwnerPartDisplayMode=1|Location.X=430|Location.Y=816|Corner.X=450|Corner.Y=824|LineWidth=1|Color=16711680|AreaColor=11599871
|RECORD=2|OwnerIndex=284|OwnerPartId=1|FormalType=1|Electrical=4|PinConglomerate=32|PinLength=10|Location.X=450|Location.Y=820|Name=2|Designator=2|PinPropagationDelay=0.000000E+000
|RECORD=2|OwnerIndex=284|OwnerPartId=1|FormalType=1|Electrical=4|PinConglomerate=34|PinLength=10|Location.X=430|Location.Y=820|Name=1|Designator=1|PinPropagationDelay=0.000000E+000
|RECORD=6|OwnerIndex=284|IsNotAccesible=T|IndexInSheet=5|OwnerPartId=1|LineWidth=1|Color=16711680|LocationCount=10|X1=450|Y1=820|X2=446|Y2=820|X3=445|Y3=818|X4=443|Y4=822|X5=441|Y5=818|X6=439|Y6=822|X7=437|Y7=818|X8=435|Y8=822|X9=434|Y9=820|X10=430|Y10=820
|RECORD=41|OwnerIndex=284|IndexInSheet=6|OwnerPartId=-1|Location.X=418|Location.Y=833|Color=8388608|FontID=1|IsHidden=T|Text=CRCW040227R0FKED|Name=Part Number
|RECORD=41|OwnerIndex=284|IndexInSheet=7|OwnerPartId=-1|Location.X=418|Location.Y=833|Color=8388608|FontID=1|IsHidden=T|Text=Vishay Dale|Name=Manufacturer
|RECORD=34|OwnerIndex=284|IndexInSheet=-1|OwnerPartId=-1|Location.X=410|Location.Y=820|Color=8388608|FontID=1|Text=R43|Name=Designator|ReadOnlyState=1
|RECORD=41|OwnerIndex=284|IndexInSheet=-1|OwnerPartId=-1|Location.X=430|Location.Y=820|Color=8388608|FontID=1|Text=27_1%_0402|Name=Comment
|RECORD=44|OwnerIndex=284
|RECORD=45|OwnerIndex=299|IndexInSheet=-1|Description=Chip Resistor, 2-Leads, Body 1.00x0.50mm, IPC Medium Density|UseComponentLibrary=T|ModelName=RESC1005X40X25NL05T05|ModelType=PCBLIB|DatafileCount=1|ModelDatafileEntity0=RESC1005X40X25NL05T05|ModelDatafileKind0=PCBLib|IsCurrent=T|DatalinksLocked=T|DatabaseDatalinksLocked=T
|RECORD=46|OwnerIndex=300
|RECORD=48|OwnerIndex=300
|RECORD=41|OwnerIndex=302|IndexInSheet=-1|OwnerPartId=-1|Color=8388608|FontID=1|IsHidden=T|Text=2D|Name=Available Preview Images
|RECORD=45|OwnerIndex=299|IndexInSheet=-1|Description=Chip Resistor, 2-Leads, Body 1.00x0.50mm, IPC High Density|UseComponentLibrary=T|ModelName=RESC1005X40X25LL05T05|ModelType=PCBLIB|DatafileCount=1|ModelDatafileEntity0=RESC1005X40X25LL05T05|ModelDatafileKind0=PCBLib|DatalinksLocked=T|DatabaseDatalinksLocked=T
|RECORD=46|OwnerIndex=304
|RECORD=48|OwnerIndex=304
|RECORD=41|OwnerIndex=306|IndexInSheet=-1|OwnerPartId=-1|Color=8388608|FontID=1|IsHidden=T|Text=2D|Name=Available Preview Images
|RECORD=45|OwnerIndex=299|IndexInSheet=-1|Description=Chip Resistor, 2-Leads, Body 1.00x0.50mm, IPC Low Density|UseComponentLibrary=T|ModelName=RESC1005X40X25ML05T05|ModelType=PCBLIB|DatafileCount=1|ModelDatafileEntity0=RESC1005X40X25ML05T05|ModelDatafileKind0=PCBLib|DatalinksLocked=T|DatabaseDatalinksLocked=T
|RECORD=46|OwnerIndex=308
|RECORD=48|OwnerIndex=308
|RECORD=41|OwnerIndex=310|IndexInSheet=-1|OwnerPartId=-1|Color=8388608|FontID=1|IsHidden=T|Text=2D|Name=Available Preview Images
|RECORD=25|IndexInSheet=36|OwnerPartId=-1|Location.X=490|Location.Y=820|Color=128|FontID=1|Text=FTDI_USB_N
|RECORD=25|IndexInSheet=37|OwnerPartId=-1|Location.X=490|Location.Y=810|Color=128|FontID=1|Text=FTDI_USB_P
|RECORD=25|IndexInSheet=38|OwnerPartId=-1|Location.X=340|Location.Y=850|Color=128|FontID=1|Text=FTDI_VBUS
|RECORD=25|IndexInSheet=39|OwnerPartId=-1|Location.X=170|Location.Y=850|Color=128|FontID=1|Text=USB_VBUS
|RECORD=17|IndexInSheet=40|OwnerPartId=-1|Style=4|ShowNetName=T|Location.X=550|Location.Y=660|Orientation=3|Color=128|FontID=1|Text=GND
|RECORD=17|IndexInSheet=41|OwnerPartId=-1|Style=4|ShowNetName=T|Location.X=750|Location.Y=750|Orientation=3|Color=128|FontID=1|Text=GND
|RECORD=1|LibReference=RES|PartCount=2|DisplayModeCount=2|IndexInSheet=42|OwnerPartId=-1|Location.X=450|Location.Y=780|Orientation=2|CurrentPartId=1|SourceLibraryName=Altium Content Vault|TargetFileName=*|AreaColor=11599871|Color=128|PartIDLocked=F|DesignItemId=CMP-2002-07353-1|AllPinCount=2
|RECORD=2|OwnerIndex=318|OwnerPartId=1|OwnerPartDisplayMode=1|FormalType=1|Electrical=4|PinConglomerate=34|PinLength=10|Location.X=430|Location.Y=790|Name=2|Designator=2|PinPropagationDelay=0.000000E+000
|RECORD=2|OwnerIndex=318|OwnerPartId=1|OwnerPartDisplayMode=1|FormalType=1|Electrical=4|PinConglomerate=32|PinLength=10|Location.X=450|Location.Y=790|Name=1|Designator=1|PinPropagationDelay=0.000000E+000
|RECORD=14|OwnerIndex=318|IsNotAccesible=T|IndexInSheet=2|OwnerPartId=1|OwnerPartDisplayMode=1|Location.X=430|Location.Y=786|Corner.X=450|Corner.Y=794|LineWidth=1|Color=16711680|AreaColor=11599871
|RECORD=2|OwnerIndex=318|OwnerPartId=1|FormalType=1|Electrical=4|PinConglomerate=34|PinLength=10|Location.X=430|Location.Y=790|Name=2|Designator=2|PinPropagationDelay=0.000000E+000
|RECORD=2|OwnerIndex=318|OwnerPartId=1|FormalType=1|Electrical=4|PinConglomerate=32|PinLength=10|Location.X=450|Location.Y=790|Name=1|Designator=1|PinPropagationDelay=0.000000E+000
|RECORD=6|OwnerIndex=318|IsNotAccesible=T|IndexInSheet=5|OwnerPartId=1|LineWidth=1|Color=16711680|LocationCount=10|X1=430|Y1=790|X2=434|Y2=790|X3=435|Y3=792|X4=437|Y4=788|X5=439|Y5=792|X6=441|Y6=788|X7=443|Y7=792|X8=445|Y8=788|X9=446|Y9=790|X10=450|Y10=790
|RECORD=41|OwnerIndex=318|IndexInSheet=6|OwnerPartId=-1|Location.X=418|Location.Y=793|Color=8388608|FontID=1|IsHidden=T|Text=RC0402FR-0710KL|Name=Part Number
|RECORD=41|OwnerIndex=318|IndexInSheet=7|OwnerPartId=-1|Location.X=418|Location.Y=793|Color=8388608|FontID=1|IsHidden=T|Text=Yageo / Phycomp|Name=Manufacturer
|RECORD=34|OwnerIndex=318|IndexInSheet=-1|OwnerPartId=-1|Location.X=429|Location.Y=793|Color=8388608|FontID=1|Text=R82|Name=Designator|ReadOnlyState=1
|RECORD=41|OwnerIndex=318|IndexInSheet=-1|OwnerPartId=-1|Location.X=429|Location.Y=777|Color=8388608|FontID=1|Text=10K_1%_0402|Name=Comment
|RECORD=44|OwnerIndex=318
|RECORD=45|OwnerIndex=333|IndexInSheet=-1|Description=Chip Resistor, 2-Leads, Body 1.00x0.50mm, IPC High Density|UseComponentLibrary=T|ModelName=RESC1005X40X25LL05T10|ModelType=PCBLIB|DatafileCount=1|ModelDatafileEntity0=RESC1005X40X25LL05T10|ModelDatafileKind0=PCBLib|IsCurrent=T|DatalinksLocked=T|DatabaseDatalinksLocked=T
|RECORD=46|OwnerIndex=334
|RECORD=48|OwnerIndex=334
|RECORD=41|OwnerIndex=336|IndexInSheet=-1|OwnerPartId=-1|Color=8388608|FontID=1|IsHidden=T|Text=2D|Name=Available Preview Images
|RECORD=45|OwnerIndex=333|IndexInSheet=-1|Description=Chip Resistor, 2-Leads, Body 1.00x0.50mm, IPC Low Density|UseComponentLibrary=T|ModelName=RESC1005X40X25ML05T10|ModelType=PCBLIB|DatafileCount=1|ModelDatafileEntity0=RESC1005X40X25ML05T10|ModelDatafileKind0=PCBLib|DatalinksLocked=T|DatabaseDatalinksLocked=T
|RECORD=46|OwnerIndex=338
|RECORD=48|OwnerIndex=338
|RECORD=41|OwnerIndex=340|IndexInSheet=-1|OwnerPartId=-1|Color=8388608|FontID=1|IsHidden=T|Text=2D|Name=Available Preview Images
|RECORD=45|OwnerIndex=333|IndexInSheet=-1|Description=Chip Resistor, 2-Leads, Body 1.00x0.50mm, IPC Medium Density|UseComponentLibrary=T|ModelName=RESC1005X40X25NL05T10|ModelType=PCBLIB|DatafileCount=1|ModelDatafileEntity0=RESC1005X40X25NL05T10|ModelDatafileKind0=PCBLib|DatalinksLocked=T|DatabaseDatalinksLocked=T
|RECORD=46|OwnerIndex=342
|RECORD=48|OwnerIndex=342
|RECORD=41|OwnerIndex=344|IndexInSheet=-1|OwnerPartId=-1|Color=8388608|FontID=1|IsHidden=T|Text=2D|Name=Available Preview Images
|RECORD=17|IndexInSheet=43|OwnerPartId=-1|Style=4|ShowNetName=T|Location.X=490|Location.Y=660|Orientation=3|Color=128|FontID=1|Text=GND
|RECORD=1|LibReference=11868f565c42a9108669ba33697ecf6|ComponentDescription=CAP CER 10000PF 50V X7R 0402|PartCount=2|DisplayModeCount=1|IndexInSheet=44|OwnerPartId=-1|Location.X=450|Location.Y=740|CurrentPartId=1|LibraryPath=*|SourceLibraryName=Altium Content Vault|TargetFileName=*|AreaColor=11599871|Color=128|PartIDLocked=T|DesignItemId=CMP-2100-03592-2|AllPinCount=2
|RECORD=2|OwnerIndex=347|OwnerPartId=1|Electrical=4|PinConglomerate=49|PinLength=7|Location.X=450|Location.Y=733|Name=1|Designator=1|PinPropagationDelay=0.000000E+000
|RECORD=2|OwnerIndex=347|OwnerPartId=1|Electrical=4|PinConglomerate=51|PinLength=6|Location.X=450|Location.Y=726|Name=2|Designator=2|PinPropagationDelay=0.000000E+000
|RECORD=13|OwnerIndex=347|IsNotAccesible=T|IndexInSheet=2|OwnerPartId=1|Location.X=460|Location.Y=733|Corner.X=440|Corner.Y=733|LineWidth=1|Color=16711680
|RECORD=13|OwnerIndex=347|IsNotAccesible=T|IndexInSheet=3|OwnerPartId=1|Location.X=460|Location.Y=727|Corner.X=440|Corner.Y=727|LineWidth=1|Color=16711680
|RECORD=13|OwnerIndex=347|IsNotAccesible=T|IndexInSheet=4|OwnerPartId=1|Location.X=450|Location.Y=733|Corner.X=450|Corner.Y=736|LineWidth=1|Color=16711680
|RECORD=13|OwnerIndex=347|IsNotAccesible=T|IndexInSheet=5|OwnerPartId=1|Location.X=450|Location.Y=726|Corner.X=450|Corner.Y=725|LineWidth=1|Color=16711680
|RECORD=41|OwnerIndex=347|IndexInSheet=6|OwnerPartId=-1|Location.X=439|Location.Y=742|Color=8388608|FontID=1|IsHidden=T|Text=Ceramic Capacitors|Name=Device Class L3
|RECORD=41|OwnerIndex=347|IndexInSheet=7|OwnerPartId=-1|Location.X=439|Location.Y=742|Color=8388608|FontID=1|IsHidden=T|Text=-55°C to +125°C|Name=Temperature
|RECORD=41|OwnerIndex=347|IndexInSheet=8|OwnerPartId=-1|Location.X=439|Location.Y=742|Color=8388608|FontID=3|IsHidden=T|Text=http://www.yageo.com/exep/pages/download/literatures/UPY-C_GEN_24.pdf|Name=Footprint Url
|RECORD=41|OwnerIndex=347|IndexInSheet=9|OwnerPartId=-1|Location.X=439|Location.Y=742|Color=8388608|FontID=1|IsHidden=T|Text=CAPC10050X50|Name=Ipc Land Pattern Name
|RECORD=41|OwnerIndex=347|IndexInSheet=10|OwnerPartId=-1|Location.X=439|Location.Y=742|Color=8388608|FontID=1|IsHidden=T|Text=Passive Components|Name=Device Class L1
|RECORD=41|OwnerIndex=347|IndexInSheet=11|OwnerPartId=-1|Location.X=439|Location.Y=742|Color=8388608|FontID=1|IsHidden=T|Text=No|Name=Automotive
|RECORD=41|OwnerIndex=347|IndexInSheet=12|OwnerPartId=-1|Location.X=439|Location.Y=742|Color=8388608|FontID=3|IsHidden=T|Text=https://octopart.com/cc0402krx7r9bb103-yageo-8376513|Name=Octopart
|RECORD=41|OwnerIndex=347|IndexInSheet=13|OwnerPartId=-1|Location.X=439|Location.Y=742|Color=8388608|FontID=1|IsHidden=T|Text=30ppm/°C|Name=Temperature Coefficient
|RECORD=41|OwnerIndex=347|IndexInSheet=14|OwnerPartId=-1|Location.X=439|Location.Y=742|Color=8388608|FontID=1|IsHidden=T|Text=CC0402KRX7R9BB103|Name=Manufacturer Part Number
|RECORD=41|OwnerIndex=347|IndexInSheet=15|OwnerPartId=-1|Location.X=439|Location.Y=742|Color=8388608|FontID=1|IsHidden=T|Text=Yes|Name=Lead Free
|RECORD=41|OwnerIndex=347|IndexInSheet=16|OwnerPartId=-1|Location.X=439|Location.Y=742|Color=8388608|FontID=1|IsHidden=T|Text=-55°C|Name=Temperature Range Low
|RECORD=41|OwnerIndex=347|IndexInSheet=17|OwnerPartId=-1|Location.X=439|Location.Y=742|Color=8388608|FontID=1|IsHidden=T|Text=0.55mm|Name=Height
|RECORD=41|OwnerIndex=347|IndexInSheet=18|OwnerPartId=-1|Location.X=439|Location.Y=742|Color=8388608|FontID=3|IsHidden=T|Text=http://www.yageo.com/documents/recent/UPY-GP_NP0_16V-to-50V_16.pdf|Name=ComponentLink2URL
|RECORD=41|OwnerIndex=347|IndexInSheet=19|OwnerPartId=-1|Location.X=439|Location.Y=742|Color=8388608|FontID=1|IsHidden=T|Text=10 nF|Name=Capacitance
|RECORD=41|OwnerIndex=347|IndexInSheet=20|OwnerPartId=-1|Location.X=439|Location.Y=742|Color=8388608|FontID=1|IsHidden=T|Text=Cap|Name=Category
|RECORD=41|OwnerIndex=347|IndexInSheet=21|OwnerPartId=-1|Location.X=439|Location.Y=742|Color=8388608|FontID=1|IsHidden=T|Text=Ceramic|Name=Material
|RECORD=41|OwnerIndex=347|IndexInSheet=22|OwnerPartId=-1|Location.X=439|Location.Y=742|Color=8388608|FontID=1|IsHidden=T|Text=YAGEO|Name=Manufacturer
|RECORD=41|OwnerIndex=347|IndexInSheet=23|OwnerPartId=-1|Location.X=439|Location.Y=742|Color=8388608|FontID=1|IsHidden=T|Text=Datasheet|Name=ComponentLink2Description
|RECORD=41|OwnerIndex=347|IndexInSheet=24|OwnerPartId=-1|Location.X=439|Location.Y=742|Color=8388608|FontID=1|IsHidden=T|Text=+125°C|Name=Temperature Range High
|RECORD=41|OwnerIndex=347|IndexInSheet=25|OwnerPartId=-1|Location.X=439|Location.Y=742|Color=8388608|FontID=1|IsHidden=T|Text=CAP CER 10000PF 50V X7R 0402|Name=Digikey Description
|RECORD=41|OwnerIndex=347|IndexInSheet=26|OwnerPartId=-1|Location.X=439|Location.Y=742|Color=8388608|FontID=1|IsHidden=T|Text=50 V|Name=Voltage Rating
|RECORD=41|OwnerIndex=347|IndexInSheet=27|OwnerPartId=-1|Location.X=439|Location.Y=742|Color=8388608|FontID=1|IsHidden=T|Text=NA|Name=Automotive Grade
|RECORD=41|OwnerIndex=347|IndexInSheet=28|OwnerPartId=-1|Location.X=439|Location.Y=742|Color=8388608|FontID=1|IsHidden=T|Text=CC0402|Name=Package
|RECORD=41|OwnerIndex=347|IndexInSheet=29|OwnerPartId=-1|Location.X=439|Location.Y=742|Color=8388608|FontID=1|IsHidden=T|Text=Capacitors|Name=Device Class L2
|RECORD=41|OwnerIndex=347|IndexInSheet=30|OwnerPartId=-1|Location.X=439|Location.Y=742|Color=8388608|FontID=1|IsHidden=T|Text=0402 10 nF 50 V ±10 % Tolerance X7R SMT Multilayer Ceramic Capacitor|Name=Mouser Description
|RECORD=41|OwnerIndex=347|IndexInSheet=31|OwnerPartId=-1|Location.X=439|Location.Y=742|Color=8388608|FontID=1|IsHidden=T|Text=0.1|Name=Tolerance
|RECORD=41|OwnerIndex=347|IndexInSheet=32|OwnerPartId=-1|Location.X=439|Location.Y=742|Color=8388608|FontID=1|IsHidden=T|Text=10 nF|Name=Value
|RECORD=41|OwnerIndex=347|IndexInSheet=33|OwnerPartId=-1|Location.X=439|Location.Y=742|Color=8388608|FontID=1|IsHidden=T|Text=TRUE|Name=RoHS
|RECORD=41|OwnerIndex=347|IndexInSheet=34|OwnerPartId=-1|Location.X=439|Location.Y=742|Color=8388608|FontID=1|IsHidden=T|Text=X7R|Name=Temperature Characteristic
|RECORD=34|OwnerIndex=347|IndexInSheet=-1|OwnerPartId=-1|Location.X=440|Location.Y=720|Orientation=1|Color=8388608|FontID=2|Text=C91|Name=Designator|ReadOnlyState=1
|RECORD=41|OwnerIndex=347|IndexInSheet=-1|OwnerPartId=1|Location.X=470|Location.Y=700|Orientation=1|Color=8388608|FontID=2|Text=10nF_50V_0402|Name=Comment
|RECORD=44|OwnerIndex=347
|RECORD=45|OwnerIndex=387|IndexInSheet=-1|UseComponentLibrary=T|ModelName=FP-CC0402-MFG|ModelType=PCBLIB|DatafileCount=1|ModelDatafileEntity0=FP-CC0402-MFG|ModelDatafileKind0=PCBLib|IsCurrent=T|DatalinksLocked=T|DatabaseDatalinksLocked=T
|RECORD=46|OwnerIndex=388
|RECORD=48|OwnerIndex=388
|RECORD=45|OwnerIndex=387|IndexInSheet=-1|UseComponentLibrary=T|ModelName=FP-CC0402-IPC_C|ModelType=PCBLIB|DatafileCount=1|ModelDatafileEntity0=FP-CC0402-IPC_C|ModelDatafileKind0=PCBLib|DatalinksLocked=T|DatabaseDatalinksLocked=T
|RECORD=46|OwnerIndex=391
|RECORD=48|OwnerIndex=391
|RECORD=45|OwnerIndex=387|IndexInSheet=-1|UseComponentLibrary=T|ModelName=FP-CC0402-IPC_B|ModelType=PCBLIB|DatafileCount=1|ModelDatafileEntity0=FP-CC0402-IPC_B|ModelDatafileKind0=PCBLib|DatalinksLocked=T|DatabaseDatalinksLocked=T
|RECORD=46|OwnerIndex=394
|RECORD=48|OwnerIndex=394
|RECORD=45|OwnerIndex=387|IndexInSheet=-1|UseComponentLibrary=T|ModelName=FP-CC0402-IPC_A|ModelType=PCBLIB|DatafileCount=1|ModelDatafileEntity0=FP-CC0402-IPC_A|ModelDatafileKind0=PCBLib|DatalinksLocked=T|DatabaseDatalinksLocked=T
|RECORD=46|OwnerIndex=397
|RECORD=48|OwnerIndex=397
|RECORD=1|LibReference=RES|PartCount=2|DisplayModeCount=2|IndexInSheet=45|OwnerPartId=-1|Location.X=780|Location.Y=860|CurrentPartId=1|SourceLibraryName=Altium Content Vault|TargetFileName=*|AreaColor=11599871|Color=128|PartIDLocked=F|DesignItemId=CMP-2002-08434-1|AllPinCount=2
|RECORD=2|OwnerIndex=400|OwnerPartId=1|OwnerPartDisplayMode=1|FormalType=1|Electrical=4|PinConglomerate=32|PinLength=10|Location.X=800|Location.Y=850|Name=2|Designator=2|PinPropagationDelay=0.000000E+000
|RECORD=2|OwnerIndex=400|OwnerPartId=1|OwnerPartDisplayMode=1|FormalType=1|Electrical=4|PinConglomerate=34|PinLength=10|Location.X=780|Location.Y=850|Name=1|Designator=1|PinPropagationDelay=0.000000E+000
|RECORD=14|OwnerIndex=400|IsNotAccesible=T|IndexInSheet=2|OwnerPartId=1|OwnerPartDisplayMode=1|Location.X=780|Location.Y=846|Corner.X=800|Corner.Y=854|LineWidth=1|Color=16711680|AreaColor=11599871
|RECORD=2|OwnerIndex=400|OwnerPartId=1|FormalType=1|Electrical=4|PinConglomerate=32|PinLength=10|Location.X=800|Location.Y=850|Name=2|Designator=2|PinPropagationDelay=0.000000E+000
|RECORD=2|OwnerIndex=400|OwnerPartId=1|FormalType=1|Electrical=4|PinConglomerate=34|PinLength=10|Location.X=780|Location.Y=850|Name=1|Designator=1|PinPropagationDelay=0.000000E+000
|RECORD=6|OwnerIndex=400|IsNotAccesible=T|IndexInSheet=5|OwnerPartId=1|LineWidth=1|Color=16711680|LocationCount=10|X1=800|Y1=850|X2=796|Y2=850|X3=795|Y3=848|X4=793|Y4=852|X5=791|Y5=848|X6=789|Y6=852|X7=787|Y7=848|X8=785|Y8=852|X9=784|Y9=850|X10=780|Y10=850
|RECORD=41|OwnerIndex=400|IndexInSheet=6|OwnerPartId=-1|Location.X=768|Location.Y=863|Color=8388608|FontID=1|IsHidden=T|Text=CRCW040227R0FKED|Name=Part Number
|RECORD=41|OwnerIndex=400|IndexInSheet=7|OwnerPartId=-1|Location.X=768|Location.Y=863|Color=8388608|FontID=1|IsHidden=T|Text=Vishay Dale|Name=Manufacturer
|RECORD=34|OwnerIndex=400|IndexInSheet=-1|OwnerPartId=-1|Location.X=760|Location.Y=850|Color=8388608|FontID=1|Text=R13|Name=Designator|ReadOnlyState=1
|RECORD=41|OwnerIndex=400|IndexInSheet=-1|OwnerPartId=-1|Location.X=780|Location.Y=850|Color=8388608|FontID=1|Text=27_1%_0402|Name=Comment
|RECORD=44|OwnerIndex=400
|RECORD=45|OwnerIndex=415|IndexInSheet=-1|Description=Chip Resistor, 2-Leads, Body 1.00x0.50mm, IPC Medium Density|UseComponentLibrary=T|ModelName=RESC1005X40X25NL05T05|ModelType=PCBLIB|DatafileCount=1|ModelDatafileEntity0=RESC1005X40X25NL05T05|ModelDatafileKind0=PCBLib|IsCurrent=T|DatalinksLocked=T|DatabaseDatalinksLocked=T
|RECORD=46|OwnerIndex=416
|RECORD=48|OwnerIndex=416
|RECORD=41|OwnerIndex=418|IndexInSheet=-1|OwnerPartId=-1|Color=8388608|FontID=1|IsHidden=T|Text=2D|Name=Available Preview Images
|RECORD=45|OwnerIndex=415|IndexInSheet=-1|Description=Chip Resistor, 2-Leads, Body 1.00x0.50mm, IPC High Density|UseComponentLibrary=T|ModelName=RESC1005X40X25LL05T05|ModelType=PCBLIB|DatafileCount=1|ModelDatafileEntity0=RESC1005X40X25LL05T05|ModelDatafileKind0=PCBLib|DatalinksLocked=T|DatabaseDatalinksLocked=T
|RECORD=46|OwnerIndex=420
|RECORD=48|OwnerIndex=420
|RECORD=41|OwnerIndex=422|IndexInSheet=-1|OwnerPartId=-1|Color=8388608|FontID=1|IsHidden=T|Text=2D|Name=Available Preview Images
|RECORD=45|OwnerIndex=415|IndexInSheet=-1|Description=Chip Resistor, 2-Leads, Body 1.00x0.50mm, IPC Low Density|UseComponentLibrary=T|ModelName=RESC1005X40X25ML05T05|ModelType=PCBLIB|DatafileCount=1|ModelDatafileEntity0=RESC1005X40X25ML05T05|ModelDatafileKind0=PCBLib|DatalinksLocked=T|DatabaseDatalinksLocked=T
|RECORD=46|OwnerIndex=424
|RECORD=48|OwnerIndex=424
|RECORD=41|OwnerIndex=426|IndexInSheet=-1|OwnerPartId=-1|Color=8388608|FontID=1|IsHidden=T|Text=2D|Name=Available Preview Images
|RECORD=1|LibReference=RES|PartCount=2|DisplayModeCount=2|IndexInSheet=46|OwnerPartId=-1|Location.X=780|Location.Y=850|CurrentPartId=1|SourceLibraryName=Altium Content Vault|TargetFileName=*|AreaColor=11599871|Color=128|PartIDLocked=F|DesignItemId=CMP-2002-08434-1|AllPinCount=2
|RECORD=2|OwnerIndex=428|OwnerPartId=1|OwnerPartDisplayMode=1|FormalType=1|Electrical=4|PinConglomerate=32|PinLength=10|Location.X=800|Location.Y=840|Name=2|Designator=2|PinPropagationDelay=0.000000E+000
|RECORD=2|OwnerIndex=428|OwnerPartId=1|OwnerPartDisplayMode=1|FormalType=1|Electrical=4|PinConglomerate=34|PinLength=10|Location.X=780|Location.Y=840|Name=1|Designator=1|PinPropagationDelay=0.000000E+000
|RECORD=14|OwnerIndex=428|IsNotAccesible=T|IndexInSheet=2|OwnerPartId=1|OwnerPartDisplayMode=1|Location.X=780|Location.Y=836|Corner.X=800|Corner.Y=844|LineWidth=1|Color=16711680|AreaColor=11599871
|RECORD=2|OwnerIndex=428|OwnerPartId=1|FormalType=1|Electrical=4|PinConglomerate=32|PinLength=10|Location.X=800|Location.Y=840|Name=2|Designator=2|PinPropagationDelay=0.000000E+000
|RECORD=2|OwnerIndex=428|OwnerPartId=1|FormalType=1|Electrical=4|PinConglomerate=34|PinLength=10|Location.X=780|Location.Y=840|Name=1|Designator=1|PinPropagationDelay=0.000000E+000
|RECORD=6|OwnerIndex=428|IsNotAccesible=T|IndexInSheet=5|OwnerPartId=1|LineWidth=1|Color=16711680|LocationCount=10|X1=800|Y1=840|X2=796|Y2=840|X3=795|Y3=838|X4=793|Y4=842|X5=791|Y5=838|X6=789|Y6=842|X7=787|Y7=838|X8=785|Y8=842|X9=784|Y9=840|X10=780|Y10=840
|RECORD=41|OwnerIndex=428|IndexInSheet=6|OwnerPartId=-1|Location.X=768|Location.Y=853|Color=8388608|FontID=1|IsHidden=T|Text=CRCW040227R0FKED|Name=Part Number
|RECORD=41|OwnerIndex=428|IndexInSheet=7|OwnerPartId=-1|Location.X=768|Location.Y=853|Color=8388608|FontID=1|IsHidden=T|Text=Vishay Dale|Name=Manufacturer
|RECORD=34|OwnerIndex=428|IndexInSheet=-1|OwnerPartId=-1|Location.X=760|Location.Y=840|Color=8388608|FontID=1|Text=R42|Name=Designator|ReadOnlyState=1
|RECORD=41|OwnerIndex=428|IndexInSheet=-1|OwnerPartId=-1|Location.X=780|Location.Y=840|Color=8388608|FontID=1|Text=27_1%_0402|Name=Comment
|RECORD=44|OwnerIndex=428
|RECORD=45|OwnerIndex=443|IndexInSheet=-1|Description=Chip Resistor, 2-Leads, Body 1.00x0.50mm, IPC Medium Density|UseComponentLibrary=T|ModelName=RESC1005X40X25NL05T05|ModelType=PCBLIB|DatafileCount=1|ModelDatafileEntity0=RESC1005X40X25NL05T05|ModelDatafileKind0=PCBLib|IsCurrent=T|DatalinksLocked=T|DatabaseDatalinksLocked=T
|RECORD=46|OwnerIndex=444
|RECORD=48|OwnerIndex=444
|RECORD=41|OwnerIndex=446|IndexInSheet=-1|OwnerPartId=-1|Color=8388608|FontID=1|IsHidden=T|Text=2D|Name=Available Preview Images
|RECORD=45|OwnerIndex=443|IndexInSheet=-1|Description=Chip Resistor, 2-Leads, Body 1.00x0.50mm, IPC High Density|UseComponentLibrary=T|ModelName=RESC1005X40X25LL05T05|ModelType=PCBLIB|DatafileCount=1|ModelDatafileEntity0=RESC1005X40X25LL05T05|ModelDatafileKind0=PCBLib|DatalinksLocked=T|DatabaseDatalinksLocked=T
|RECORD=46|OwnerIndex=448
|RECORD=48|OwnerIndex=448
|RECORD=41|OwnerIndex=450|IndexInSheet=-1|OwnerPartId=-1|Color=8388608|FontID=1|IsHidden=T|Text=2D|Name=Available Preview Images
|RECORD=45|OwnerIndex=443|IndexInSheet=-1|Description=Chip Resistor, 2-Leads, Body 1.00x0.50mm, IPC Low Density|UseComponentLibrary=T|ModelName=RESC1005X40X25ML05T05|ModelType=PCBLIB|DatafileCount=1|ModelDatafileEntity0=RESC1005X40X25ML05T05|ModelDatafileKind0=PCBLib|DatalinksLocked=T|DatabaseDatalinksLocked=T
|RECORD=46|OwnerIndex=452
|RECORD=48|OwnerIndex=452
|RECORD=41|OwnerIndex=454|IndexInSheet=-1|OwnerPartId=-1|Color=8388608|FontID=1|IsHidden=T|Text=2D|Name=Available Preview Images
|RECORD=17|IndexInSheet=47|OwnerPartId=-1|Style=1|ShowNetName=T|Location.X=870|Location.Y=850|Color=255|FontID=1|Text=FTDI_TX|IsCrossSheetConnector=T
|RECORD=17|IndexInSheet=48|OwnerPartId=-1|ShowNetName=T|Location.X=870|Location.Y=840|Color=255|FontID=1|Text=FTDI_RX|IsCrossSheetConnector=T
|RECORD=1|LibReference=b4654b650e69147ec39a6b967a45e02|ComponentDescription=General Purpose Ceramic Capacitor, 0402, 100nF, 10%, X7R, 15%, 25V|PartCount=2|DisplayModeCount=1|IndexInSheet=49|OwnerPartId=-1|Location.X=340|Location.Y=770|CurrentPartId=1|LibraryPath=*|SourceLibraryName=Altium Content Vault|TargetFileName=*|AreaColor=11599871|Color=128|PartIDLocked=T|DesignItemId=CMP-2008-02519-2|AllPinCount=2
|RECORD=2|OwnerIndex=458|OwnerPartId=1|Electrical=4|PinConglomerate=49|PinLength=7|Location.X=340|Location.Y=763|Name=1|Designator=1|PinPropagationDelay=0.000000E+000
|RECORD=2|OwnerIndex=458|OwnerPartId=1|Electrical=4|PinConglomerate=51|PinLength=6|Location.X=340|Location.Y=756|Name=2|Designator=2|PinPropagationDelay=0.000000E+000
|RECORD=13|OwnerIndex=458|IsNotAccesible=T|IndexInSheet=2|OwnerPartId=1|Location.X=350|Location.Y=763|Corner.X=330|Corner.Y=763|LineWidth=1|Color=16711680
|RECORD=13|OwnerIndex=458|IsNotAccesible=T|IndexInSheet=3|OwnerPartId=1|Location.X=350|Location.Y=757|Corner.X=330|Corner.Y=757|LineWidth=1|Color=16711680
|RECORD=13|OwnerIndex=458|IsNotAccesible=T|IndexInSheet=4|OwnerPartId=1|Location.X=340|Location.Y=763|Corner.X=340|Corner.Y=766|LineWidth=1|Color=16711680
|RECORD=13|OwnerIndex=458|IsNotAccesible=T|IndexInSheet=5|OwnerPartId=1|Location.X=340|Location.Y=756|Corner.X=340|Corner.Y=755|LineWidth=1|Color=16711680
|RECORD=41|OwnerIndex=458|IndexInSheet=6|OwnerPartId=-1|Location.X=329|Location.Y=772|Color=8388608|FontID=1|IsHidden=T|Text=1|Name=Package Quantity
|RECORD=41|OwnerIndex=458|IndexInSheet=7|OwnerPartId=-1|Location.X=329|Location.Y=772|Color=8388608|FontID=1|IsHidden=T|Text=100nF|Name=Capacitance
|RECORD=41|OwnerIndex=458|IndexInSheet=8|OwnerPartId=-1|Location.X=329|Location.Y=772|Color=8388608|FontID=1|IsHidden=T|Text=-55°C|Name=Min Operating Temperature
|RECORD=41|OwnerIndex=458|IndexInSheet=9|OwnerPartId=-1|Location.X=329|Location.Y=772|Color=8388608|FontID=1|IsHidden=T|Text=25V|Name=Voltage
|RECORD=41|OwnerIndex=458|IndexInSheet=10|OwnerPartId=-1|Location.X=329|Location.Y=772|Color=8388608|FontID=1|IsHidden=T|Text=25V|Name=Voltage Rating
|RECORD=41|OwnerIndex=458|IndexInSheet=11|OwnerPartId=-1|Location.X=329|Location.Y=772|Color=8388608|FontID=1|IsHidden=T|Text=Flat|Name=Construction
|RECORD=41|OwnerIndex=458|IndexInSheet=12|OwnerPartId=-1|Location.X=329|Location.Y=772|Color=8388608|FontID=1|IsHidden=T|Text=125°C|Name=Max Operating Temperature
|RECORD=41|OwnerIndex=458|IndexInSheet=13|OwnerPartId=-1|Location.X=329|Location.Y=772|Color=8388608|FontID=1|IsHidden=T|Text=No|Name=Radiation Hardening
|RECORD=41|OwnerIndex=458|IndexInSheet=14|OwnerPartId=-1|Location.X=329|Location.Y=772|Color=8388608|FontID=1|IsHidden=T|Text=0.5mm|Name=Depth
|RECORD=41|OwnerIndex=458|IndexInSheet=15|OwnerPartId=-1|Location.X=329|Location.Y=772|Color=8388608|FontID=1|IsHidden=T|Text=0.022inch|Name=Thickness
|RECORD=41|OwnerIndex=458|IndexInSheet=16|OwnerPartId=-1|Location.X=329|Location.Y=772|Color=8388608|FontID=1|IsHidden=T|Text=25V|Name=Voltage Rating (DC)
|RECORD=41|OwnerIndex=458|IndexInSheet=17|OwnerPartId=-1|Location.X=329|Location.Y=772|Color=8388608|FontID=1|IsHidden=T|Text=2|Name=Number of Pins
|RECORD=41|OwnerIndex=458|IndexInSheet=18|OwnerPartId=-1|Location.X=329|Location.Y=772|Color=8388608|FontID=1|IsHidden=T|Text=Lead Free|Name=Lead Free
|RECORD=41|OwnerIndex=458|IndexInSheet=19|OwnerPartId=-1|Location.X=329|Location.Y=772|Color=8388608|FontID=1|IsHidden=T|Text=-|Name=Series
|RECORD=41|OwnerIndex=458|IndexInSheet=20|OwnerPartId=-1|Location.X=329|Location.Y=772|Color=8388608|FontID=1|IsHidden=T|Text=No SVHC|Name=REACH SVHC
|RECORD=41|OwnerIndex=458|IndexInSheet=21|OwnerPartId=-1|Location.X=329|Location.Y=772|Color=8388608|FontID=1|IsHidden=T|Text=1mm|Name=Length
|RECORD=41|OwnerIndex=458|IndexInSheet=22|OwnerPartId=-1|Location.X=329|Location.Y=772|Color=8388608|FontID=1|IsHidden=T|Text=X7R|Name=Dielectric
|RECORD=41|OwnerIndex=458|IndexInSheet=23|OwnerPartId=-1|Location.X=329|Location.Y=772|Color=8388608|FontID=1|IsHidden=T|Text=Yes|Name=RoHS Compliant
|RECORD=41|OwnerIndex=458|IndexInSheet=24|OwnerPartId=-1|Location.X=329|Location.Y=772|Color=8388608|FontID=1|IsHidden=T|Text=Surface Mount|Name=Mount
|RECORD=41|OwnerIndex=458|IndexInSheet=25|OwnerPartId=-1|Location.X=329|Location.Y=772|Color=8388608|FontID=1|IsHidden=T|Text=Tape and Reel|Name=Packaging
|RECORD=41|OwnerIndex=458|IndexInSheet=26|OwnerPartId=-1|Location.X=329|Location.Y=772|Color=8388608|FontID=1|IsHidden=T|Text=0402|Name=Case/Package
|RECORD=41|OwnerIndex=458|IndexInSheet=27|OwnerPartId=-1|Location.X=329|Location.Y=772|Color=8388608|FontID=1|IsHidden=T|Text=0402|Name=Case Code (Imperial)
|RECORD=41|OwnerIndex=458|IndexInSheet=28|OwnerPartId=-1|Location.X=329|Location.Y=772|Color=8388608|FontID=1|IsHidden=T|Text=SMD/SMT|Name=Termination
|RECORD=41|OwnerIndex=458|IndexInSheet=29|OwnerPartId=-1|Location.X=329|Location.Y=772|Color=8388608|FontID=1|IsHidden=T|Text=0.02inch|Name=Width
|RECORD=41|OwnerIndex=458|IndexInSheet=30|OwnerPartId=-1|Location.X=329|Location.Y=772|Color=8388608|FontID=1|IsHidden=T|Text=1005|Name=Case Code (Metric)
|RECORD=41|OwnerIndex=458|IndexInSheet=31|OwnerPartId=-1|Location.X=329|Location.Y=772|Color=8388608|FontID=1|IsHidden=T|Text=10%|Name=Tolerance
|RECORD=34|OwnerIndex=458|IndexInSheet=-1|OwnerPartId=-1|Location.X=330|Location.Y=750|Orientation=1|Color=8388608|FontID=2|Text=C89|Name=Designator|ReadOnlyState=1
|RECORD=41|OwnerIndex=458|IndexInSheet=-1|OwnerPartId=1|Location.X=360|Location.Y=735|Orientation=1|Color=8388608|FontID=2|Text=0.1uF_25V_0402|Name=Comment
|RECORD=44|OwnerIndex=458
|RECORD=45|OwnerIndex=495|IndexInSheet=-1|UseComponentLibrary=T|ModelName=FP-0402-L_1_0_1-W_0_5_0_1-IPC_C|ModelType=PCBLIB|DatafileCount=1|ModelDatafileEntity0=FP-0402-L_1_0_1-W_0_5_0_1-IPC_C|ModelDatafileKind0=PCBLib|IsCurrent=T|DatalinksLocked=T|DatabaseDatalinksLocked=T
|RECORD=46|OwnerIndex=496
|RECORD=48|OwnerIndex=496
|RECORD=45|OwnerIndex=495|IndexInSheet=-1|UseComponentLibrary=T|ModelName=FP-0402-L_1_0_1-W_0_5_0_1-IPC_B|ModelType=PCBLIB|DatafileCount=1|ModelDatafileEntity0=FP-0402-L_1_0_1-W_0_5_0_1-IPC_B|ModelDatafileKind0=PCBLib|DatalinksLocked=T|DatabaseDatalinksLocked=T
|RECORD=46|OwnerIndex=499
|RECORD=48|OwnerIndex=499
|RECORD=45|OwnerIndex=495|IndexInSheet=-1|UseComponentLibrary=T|ModelName=FP-0402-L_1_0_1-W_0_5_0_1-MFG|ModelType=PCBLIB|DatafileCount=1|ModelDatafileEntity0=FP-0402-L_1_0_1-W_0_5_0_1-MFG|ModelDatafileKind0=PCBLib|DatalinksLocked=T|DatabaseDatalinksLocked=T
|RECORD=46|OwnerIndex=502
|RECORD=48|OwnerIndex=502
|RECORD=45|OwnerIndex=495|IndexInSheet=-1|UseComponentLibrary=T|ModelName=FP-0402-L_1_0_1-W_0_5_0_1-IPC_A|ModelType=PCBLIB|DatafileCount=1|ModelDatafileEntity0=FP-0402-L_1_0_1-W_0_5_0_1-IPC_A|ModelDatafileKind0=PCBLib|DatalinksLocked=T|DatabaseDatalinksLocked=T
|RECORD=46|OwnerIndex=505
|RECORD=48|OwnerIndex=505
|RECORD=1|LibReference=b4654b650e69147ec39a6b967a45e02|ComponentDescription=Cap Ceramic 4.7uF 16V X5R ±20% SMD 0402 +85°C Paper T/R|PartCount=2|DisplayModeCount=1|IndexInSheet=50|OwnerPartId=-1|Location.X=380|Location.Y=770|CurrentPartId=1|LibraryPath=*|SourceLibraryName=Altium Content Vault|TargetFileName=*|AreaColor=11599871|Color=128|PartIDLocked=T|DesignItemId=CMP-13271-001468-1|AllPinCount=2
|RECORD=2|OwnerIndex=508|OwnerPartId=1|Electrical=4|PinConglomerate=49|PinLength=7|Location.X=380|Location.Y=763|Name=1|Designator=1|PinPropagationDelay=0.000000E+000
|RECORD=2|OwnerIndex=508|OwnerPartId=1|Electrical=4|PinConglomerate=51|PinLength=6|Location.X=380|Location.Y=756|Name=2|Designator=2|PinPropagationDelay=0.000000E+000
|RECORD=13|OwnerIndex=508|IsNotAccesible=T|IndexInSheet=2|OwnerPartId=1|Location.X=390|Location.Y=763|Corner.X=370|Corner.Y=763|LineWidth=1|Color=16711680
|RECORD=13|OwnerIndex=508|IsNotAccesible=T|IndexInSheet=3|OwnerPartId=1|Location.X=390|Location.Y=757|Corner.X=370|Corner.Y=757|LineWidth=1|Color=16711680
|RECORD=13|OwnerIndex=508|IsNotAccesible=T|IndexInSheet=4|OwnerPartId=1|Location.X=380|Location.Y=763|Corner.X=380|Corner.Y=766|LineWidth=1|Color=16711680
|RECORD=13|OwnerIndex=508|IsNotAccesible=T|IndexInSheet=5|OwnerPartId=1|Location.X=380|Location.Y=756|Corner.X=380|Corner.Y=755|LineWidth=1|Color=16711680
|RECORD=41|OwnerIndex=508|IndexInSheet=6|OwnerPartId=-1|Location.X=369|Location.Y=772|Color=8388608|FontID=1|IsHidden=T|Text=Surface Mount|Name=Mount
|RECORD=41|OwnerIndex=508|IndexInSheet=7|OwnerPartId=-1|Location.X=369|Location.Y=772|Color=8388608|FontID=1|IsHidden=T|Text=1005|Name=Case Code (Metric)
|RECORD=41|OwnerIndex=508|IndexInSheet=8|OwnerPartId=-1|Location.X=369|Location.Y=772|Color=8388608|FontID=1|IsHidden=T|Text=0402|Name=Case/Package
|RECORD=41|OwnerIndex=508|IndexInSheet=9|OwnerPartId=-1|Location.X=369|Location.Y=772|Color=8388608|FontID=1|IsHidden=T|Text=0.039inch|Name=Length
|RECORD=41|OwnerIndex=508|IndexInSheet=10|OwnerPartId=-1|Location.X=369|Location.Y=772|Color=8388608|FontID=1|IsHidden=T|Text=4.7uF|Name=Capacitance
|RECORD=41|OwnerIndex=508|IndexInSheet=11|OwnerPartId=-1|Location.X=369|Location.Y=772|Color=8388608|FontID=1|IsHidden=T|Text=16V|Name=Voltage Rating
|RECORD=41|OwnerIndex=508|IndexInSheet=12|OwnerPartId=-1|Location.X=369|Location.Y=772|Color=8388608|FontID=1|IsHidden=T|Text=85°C|Name=Max Operating Temperature
|RECORD=41|OwnerIndex=508|IndexInSheet=13|OwnerPartId=-1|Location.X=369|Location.Y=772|Color=8388608|FontID=1|IsHidden=T|Text=20%|Name=Tolerance
|RECORD=41|OwnerIndex=508|IndexInSheet=14|OwnerPartId=-1|Location.X=369|Location.Y=772|Color=8388608|FontID=1|IsHidden=T|Text=0.022inch|Name=Thickness
|RECORD=41|OwnerIndex=508|IndexInSheet=15|OwnerPartId=-1|Location.X=369|Location.Y=772|Color=8388608|FontID=1|IsHidden=T|Text=-55°C|Name=Min Operating Temperature
|RECORD=41|OwnerIndex=508|IndexInSheet=16|OwnerPartId=-1|Location.X=369|Location.Y=772|Color=8388608|FontID=1|IsHidden=T|Text=0402|Name=Case Code (Imperial)
|RECORD=41|OwnerIndex=508|IndexInSheet=17|OwnerPartId=-1|Location.X=369|Location.Y=772|Color=8388608|FontID=1|IsHidden=T|Text=Tape and Reel|Name=Packaging
|RECORD=41|OwnerIndex=508|IndexInSheet=18|OwnerPartId=-1|Location.X=369|Location.Y=772|Color=8388608|FontID=1|IsHidden=T|Text=0.02inch|Name=Width
|RECORD=34|OwnerIndex=508|IndexInSheet=-1|OwnerPartId=-1|Location.X=370|Location.Y=750|Orientation=1|Color=8388608|FontID=2|Text=C90|Name=Designator|ReadOnlyState=1
|RECORD=41|OwnerIndex=508|IndexInSheet=-1|OwnerPartId=1|Location.X=400|Location.Y=730|Orientation=1|Color=8388608|FontID=2|Text=4.7uF_16V_0402|Name=Comment
|RECORD=44|OwnerIndex=508
|RECORD=45|OwnerIndex=532|IndexInSheet=-1|UseComponentLibrary=T|ModelName=FP-CL829-IPC_C|ModelType=PCBLIB|DatafileCount=1|ModelDatafileEntity0=FP-CL829-IPC_C|ModelDatafileKind0=PCBLib|IsCurrent=T|DatalinksLocked=T|DatabaseDatalinksLocked=T
|RECORD=46|OwnerIndex=533
|RECORD=48|OwnerIndex=533
|RECORD=45|OwnerIndex=532|IndexInSheet=-1|UseComponentLibrary=T|ModelName=FP-CL829-IPC_B|ModelType=PCBLIB|DatafileCount=1|ModelDatafileEntity0=FP-CL829-IPC_B|ModelDatafileKind0=PCBLib|DatalinksLocked=T|DatabaseDatalinksLocked=T
|RECORD=46|OwnerIndex=536
|RECORD=48|OwnerIndex=536
|RECORD=45|OwnerIndex=532|IndexInSheet=-1|UseComponentLibrary=T|ModelName=FP-CL829-IPC_A|ModelType=PCBLIB|DatafileCount=1|ModelDatafileEntity0=FP-CL829-IPC_A|ModelDatafileKind0=PCBLib|DatalinksLocked=T|DatabaseDatalinksLocked=T
|RECORD=46|OwnerIndex=539
|RECORD=48|OwnerIndex=539
|RECORD=1|LibReference=b4654b650e69147ec39a6b967a45e02|ComponentDescription=General Purpose Ceramic Capacitor, 0402, 100nF, 10%, X7R, 15%, 25V|PartCount=2|DisplayModeCount=1|IndexInSheet=51|OwnerPartId=-1|Location.X=590|Location.Y=720|CurrentPartId=1|LibraryPath=*|SourceLibraryName=Altium Content Vault|TargetFileName=*|AreaColor=11599871|Color=128|PartIDLocked=T|DesignItemId=CMP-2008-02519-2|AllPinCount=2
|RECORD=2|OwnerIndex=542|OwnerPartId=1|Electrical=4|PinConglomerate=49|PinLength=7|Location.X=590|Location.Y=713|Name=1|Designator=1|PinPropagationDelay=0.000000E+000
|RECORD=2|OwnerIndex=542|OwnerPartId=1|Electrical=4|PinConglomerate=51|PinLength=6|Location.X=590|Location.Y=706|Name=2|Designator=2|PinPropagationDelay=0.000000E+000
|RECORD=13|OwnerIndex=542|IsNotAccesible=T|IndexInSheet=2|OwnerPartId=1|Location.X=600|Location.Y=713|Corner.X=580|Corner.Y=713|LineWidth=1|Color=16711680
|RECORD=13|OwnerIndex=542|IsNotAccesible=T|IndexInSheet=3|OwnerPartId=1|Location.X=600|Location.Y=707|Corner.X=580|Corner.Y=707|LineWidth=1|Color=16711680
|RECORD=13|OwnerIndex=542|IsNotAccesible=T|IndexInSheet=4|OwnerPartId=1|Location.X=590|Location.Y=713|Corner.X=590|Corner.Y=716|LineWidth=1|Color=16711680
|RECORD=13|OwnerIndex=542|IsNotAccesible=T|IndexInSheet=5|OwnerPartId=1|Location.X=590|Location.Y=706|Corner.X=590|Corner.Y=705|LineWidth=1|Color=16711680
|RECORD=41|OwnerIndex=542|IndexInSheet=6|OwnerPartId=-1|Location.X=579|Location.Y=722|Color=8388608|FontID=1|IsHidden=T|Text=1|Name=Package Quantity
|RECORD=41|OwnerIndex=542|IndexInSheet=7|OwnerPartId=-1|Location.X=579|Location.Y=722|Color=8388608|FontID=1|IsHidden=T|Text=100nF|Name=Capacitance
|RECORD=41|OwnerIndex=542|IndexInSheet=8|OwnerPartId=-1|Location.X=579|Location.Y=722|Color=8388608|FontID=1|IsHidden=T|Text=-55°C|Name=Min Operating Temperature
|RECORD=41|OwnerIndex=542|IndexInSheet=9|OwnerPartId=-1|Location.X=579|Location.Y=722|Color=8388608|FontID=1|IsHidden=T|Text=25V|Name=Voltage
|RECORD=41|OwnerIndex=542|IndexInSheet=10|OwnerPartId=-1|Location.X=579|Location.Y=722|Color=8388608|FontID=1|IsHidden=T|Text=25V|Name=Voltage Rating
|RECORD=41|OwnerIndex=542|IndexInSheet=11|OwnerPartId=-1|Location.X=579|Location.Y=722|Color=8388608|FontID=1|IsHidden=T|Text=Flat|Name=Construction
|RECORD=41|OwnerIndex=542|IndexInSheet=12|OwnerPartId=-1|Location.X=579|Location.Y=722|Color=8388608|FontID=1|IsHidden=T|Text=125°C|Name=Max Operating Temperature
|RECORD=41|OwnerIndex=542|IndexInSheet=13|OwnerPartId=-1|Location.X=579|Location.Y=722|Color=8388608|FontID=1|IsHidden=T|Text=No|Name=Radiation Hardening
|RECORD=41|OwnerIndex=542|IndexInSheet=14|OwnerPartId=-1|Location.X=579|Location.Y=722|Color=8388608|FontID=1|IsHidden=T|Text=0.5mm|Name=Depth
|RECORD=41|OwnerIndex=542|IndexInSheet=15|OwnerPartId=-1|Location.X=579|Location.Y=722|Color=8388608|FontID=1|IsHidden=T|Text=0.022inch|Name=Thickness
|RECORD=41|OwnerIndex=542|IndexInSheet=16|OwnerPartId=-1|Location.X=579|Location.Y=722|Color=8388608|FontID=1|IsHidden=T|Text=25V|Name=Voltage Rating (DC)
|RECORD=41|OwnerIndex=542|IndexInSheet=17|OwnerPartId=-1|Location.X=579|Location.Y=722|Color=8388608|FontID=1|IsHidden=T|Text=2|Name=Number of Pins
|RECORD=41|OwnerIndex=542|IndexInSheet=18|OwnerPartId=-1|Location.X=579|Location.Y=722|Color=8388608|FontID=1|IsHidden=T|Text=Lead Free|Name=Lead Free
|RECORD=41|OwnerIndex=542|IndexInSheet=19|OwnerPartId=-1|Location.X=579|Location.Y=722|Color=8388608|FontID=1|IsHidden=T|Text=-|Name=Series
|RECORD=41|OwnerIndex=542|IndexInSheet=20|OwnerPartId=-1|Location.X=579|Location.Y=722|Color=8388608|FontID=1|IsHidden=T|Text=No SVHC|Name=REACH SVHC
|RECORD=41|OwnerIndex=542|IndexInSheet=21|OwnerPartId=-1|Location.X=579|Location.Y=722|Color=8388608|FontID=1|IsHidden=T|Text=1mm|Name=Length
|RECORD=41|OwnerIndex=542|IndexInSheet=22|OwnerPartId=-1|Location.X=579|Location.Y=722|Color=8388608|FontID=1|IsHidden=T|Text=X7R|Name=Dielectric
|RECORD=41|OwnerIndex=542|IndexInSheet=23|OwnerPartId=-1|Location.X=579|Location.Y=722|Color=8388608|FontID=1|IsHidden=T|Text=Yes|Name=RoHS Compliant
|RECORD=41|OwnerIndex=542|IndexInSheet=24|OwnerPartId=-1|Location.X=579|Location.Y=722|Color=8388608|FontID=1|IsHidden=T|Text=Surface Mount|Name=Mount
|RECORD=41|OwnerIndex=542|IndexInSheet=25|OwnerPartId=-1|Location.X=579|Location.Y=722|Color=8388608|FontID=1|IsHidden=T|Text=Tape and Reel|Name=Packaging
|RECORD=41|OwnerIndex=542|IndexInSheet=26|OwnerPartId=-1|Location.X=579|Location.Y=722|Color=8388608|FontID=1|IsHidden=T|Text=0402|Name=Case/Package
|RECORD=41|OwnerIndex=542|IndexInSheet=27|OwnerPartId=-1|Location.X=579|Location.Y=722|Color=8388608|FontID=1|IsHidden=T|Text=0402|Name=Case Code (Imperial)
|RECORD=41|OwnerIndex=542|IndexInSheet=28|OwnerPartId=-1|Location.X=579|Location.Y=722|Color=8388608|FontID=1|IsHidden=T|Text=SMD/SMT|Name=Termination
|RECORD=41|OwnerIndex=542|IndexInSheet=29|OwnerPartId=-1|Location.X=579|Location.Y=722|Color=8388608|FontID=1|IsHidden=T|Text=0.02inch|Name=Width
|RECORD=41|OwnerIndex=542|IndexInSheet=30|OwnerPartId=-1|Location.X=579|Location.Y=722|Color=8388608|FontID=1|IsHidden=T|Text=1005|Name=Case Code (Metric)
|RECORD=41|OwnerIndex=542|IndexInSheet=31|OwnerPartId=-1|Location.X=579|Location.Y=722|Color=8388608|FontID=1|IsHidden=T|Text=10%|Name=Tolerance
|RECORD=34|OwnerIndex=542|IndexInSheet=-1|OwnerPartId=-1|Location.X=580|Location.Y=700|Orientation=1|Color=8388608|FontID=2|Text=C93|Name=Designator|ReadOnlyState=1
|RECORD=41|OwnerIndex=542|IndexInSheet=-1|OwnerPartId=1|Location.X=610|Location.Y=685|Orientation=1|Color=8388608|FontID=2|Text=0.1uF_25V_0402|Name=Comment
|RECORD=44|OwnerIndex=542
|RECORD=45|OwnerIndex=579|IndexInSheet=-1|UseComponentLibrary=T|ModelName=FP-0402-L_1_0_1-W_0_5_0_1-IPC_C|ModelType=PCBLIB|DatafileCount=1|ModelDatafileEntity0=FP-0402-L_1_0_1-W_0_5_0_1-IPC_C|ModelDatafileKind0=PCBLib|IsCurrent=T|DatalinksLocked=T|DatabaseDatalinksLocked=T
|RECORD=46|OwnerIndex=580
|RECORD=48|OwnerIndex=580
|RECORD=45|OwnerIndex=579|IndexInSheet=-1|UseComponentLibrary=T|ModelName=FP-0402-L_1_0_1-W_0_5_0_1-IPC_B|ModelType=PCBLIB|DatafileCount=1|ModelDatafileEntity0=FP-0402-L_1_0_1-W_0_5_0_1-IPC_B|ModelDatafileKind0=PCBLib|DatalinksLocked=T|DatabaseDatalinksLocked=T
|RECORD=46|OwnerIndex=583
|RECORD=48|OwnerIndex=583
|RECORD=45|OwnerIndex=579|IndexInSheet=-1|UseComponentLibrary=T|ModelName=FP-0402-L_1_0_1-W_0_5_0_1-MFG|ModelType=PCBLIB|DatafileCount=1|ModelDatafileEntity0=FP-0402-L_1_0_1-W_0_5_0_1-MFG|ModelDatafileKind0=PCBLib|DatalinksLocked=T|DatabaseDatalinksLocked=T
|RECORD=46|OwnerIndex=586
|RECORD=48|OwnerIndex=586
|RECORD=45|OwnerIndex=579|IndexInSheet=-1|UseComponentLibrary=T|ModelName=FP-0402-L_1_0_1-W_0_5_0_1-IPC_A|ModelType=PCBLIB|DatafileCount=1|ModelDatafileEntity0=FP-0402-L_1_0_1-W_0_5_0_1-IPC_A|ModelDatafileKind0=PCBLib|DatalinksLocked=T|DatabaseDatalinksLocked=T
|RECORD=46|OwnerIndex=589
|RECORD=48|OwnerIndex=589
|RECORD=4|IndexInSheet=52|OwnerPartId=-1|Location.X=450|Location.Y=870|Color=8388608|FontID=1|Text=USB to UART
|RECORD=1|LibReference=12a319ab100cd6cfe745e35972674f5|ComponentDescription=IC SWITCH SPDT DUAL 12UQFN|PartCount=2|DisplayModeCount=1|IndexInSheet=53|OwnerPartId=-1|Location.X=1210|Location.Y=310|CurrentPartId=1|LibraryPath=*|SourceLibraryName=Altium Content Vault|TargetFileName=*|AreaColor=11599871|Color=128|PartIDLocked=T|DesignItemId=CMP-04892-000114-1|AllPinCount=12
|RECORD=14|OwnerIndex=593|IsNotAccesible=T|OwnerPartId=1|Location.X=1230|Location.Y=150|Corner.X=1330|Corner.Y=320|LineWidth=1|Color=128|AreaColor=11599871|IsSolid=T
|RECORD=2|OwnerIndex=593|OwnerPartId=1|Electrical=7|PinConglomerate=58|PinLength=20|Location.X=1230|Location.Y=310|Name=VCC|Designator=9|PinName_PositionConglomerate=16|Name_CustomFontID=1|PinDesignator_PositionConglomerate=16|Designator_CustomFontID=1|PinPropagationDelay=0.000000E+000
|RECORD=2|OwnerIndex=593|OwnerPartId=1|PinConglomerate=58|PinLength=20|Location.X=1230|Location.Y=210|Name=SEL1|Designator=1|PinName_PositionConglomerate=16|Name_CustomFontID=1|PinDesignator_PositionConglomerate=16|Designator_CustomFontID=1|PinPropagationDelay=0.000000E+000
|RECORD=2|OwnerIndex=593|OwnerPartId=1|PinConglomerate=58|PinLength=20|Location.X=1230|Location.Y=200|Name=SEL2|Designator=5|PinName_PositionConglomerate=16|Name_CustomFontID=1|PinDesignator_PositionConglomerate=16|Designator_CustomFontID=1|PinPropagationDelay=0.000000E+000
|RECORD=2|OwnerIndex=593|OwnerPartId=1|Electrical=4|PinConglomerate=58|PinLength=20|Location.X=1230|Location.Y=270|Name=NO1|Designator=2|PinName_PositionConglomerate=16|Name_CustomFontID=1|PinDesignator_PositionConglomerate=16|Designator_CustomFontID=1|PinPropagationDelay=0.000000E+000
|RECORD=2|OwnerIndex=593|OwnerPartId=1|Electrical=4|PinConglomerate=58|PinLength=20|Location.X=1230|Location.Y=230|Name=NO2|Designator=4|PinName_PositionConglomerate=16|Name_CustomFontID=1|PinDesignator_PositionConglomerate=16|Designator_CustomFontID=1|PinPropagationDelay=0.000000E+000
|RECORD=2|OwnerIndex=593|OwnerPartId=1|Electrical=4|PinConglomerate=56|PinLength=20|Location.X=1330|Location.Y=290|Name=COM1|Designator=11|PinName_PositionConglomerate=16|Name_CustomFontID=1|PinDesignator_PositionConglomerate=16|Designator_CustomFontID=1|PinPropagationDelay=0.000000E+000
|RECORD=2|OwnerIndex=593|OwnerPartId=1|Electrical=4|PinConglomerate=56|PinLength=20|Location.X=1330|Location.Y=250|Name=COM2|Designator=7|PinName_PositionConglomerate=16|Name_CustomFontID=1|PinDesignator_PositionConglomerate=16|Designator_CustomFontID=1|PinPropagationDelay=0.000000E+000
|RECORD=2|OwnerIndex=593|OwnerPartId=1|Electrical=3|PinConglomerate=58|PinLength=20|Location.X=1230|Location.Y=160|Name=F\L\T\|Designator=12|PinName_PositionConglomerate=16|Name_CustomFontID=1|PinDesignator_PositionConglomerate=16|Designator_CustomFontID=1|PinPropagationDelay=0.000000E+000
|RECORD=2|OwnerIndex=593|OwnerPartId=1|PinConglomerate=58|PinLength=20|Location.X=1230|Location.Y=180|Name=O\E\|Designator=6|PinName_PositionConglomerate=16|Name_CustomFontID=1|PinDesignator_PositionConglomerate=16|Designator_CustomFontID=1|PinPropagationDelay=0.000000E+000
|RECORD=2|OwnerIndex=593|OwnerPartId=1|Electrical=4|PinConglomerate=58|PinLength=20|Location.X=1230|Location.Y=290|Name=NC1|Designator=10|PinName_PositionConglomerate=16|Name_CustomFontID=1|PinDesignator_PositionConglomerate=16|Designator_CustomFontID=1|PinPropagationDelay=0.000000E+000
|RECORD=2|OwnerIndex=593|OwnerPartId=1|Electrical=4|PinConglomerate=58|PinLength=20|Location.X=1230|Location.Y=250|Name=NC2|Designator=8|PinName_PositionConglomerate=16|Name_CustomFontID=1|PinDesignator_PositionConglomerate=16|Designator_CustomFontID=1|PinPropagationDelay=0.000000E+000
|RECORD=2|OwnerIndex=593|OwnerPartId=1|Electrical=7|PinConglomerate=56|PinLength=20|Location.X=1330|Location.Y=160|Name=GND|Designator=3|PinName_PositionConglomerate=16|Name_CustomFontID=1|PinDesignator_PositionConglomerate=16|Designator_CustomFontID=1|PinPropagationDelay=0.000000E+000
|RECORD=41|OwnerIndex=593|IndexInSheet=13|OwnerPartId=-1|Location.X=1208|Location.Y=320|Color=8388608|FontID=1|IsHidden=T|Text=12|Name=Number of Pins
|RECORD=41|OwnerIndex=593|IndexInSheet=14|OwnerPartId=-1|Location.X=1208|Location.Y=320|Color=8388608|FontID=1|IsHidden=T|Text=2|Name=Number of Circuits
|RECORD=41|OwnerIndex=593|IndexInSheet=15|OwnerPartId=-1|Location.X=1208|Location.Y=320|Color=8388608|FontID=1|IsHidden=T|Text=-40°C|Name=Min Operating Temperature
|RECORD=41|OwnerIndex=593|IndexInSheet=16|OwnerPartId=-1|Location.X=1208|Location.Y=320|Color=8388608|FontID=1|IsHidden=T|Text=Yes|Name=RoHS Compliant
|RECORD=41|OwnerIndex=593|IndexInSheet=17|OwnerPartId=-1|Location.X=1208|Location.Y=320|Color=8388608|FontID=1|IsHidden=T|Text=1.2GHz|Name=-3db Bandwidth
|RECORD=41|OwnerIndex=593|IndexInSheet=18|OwnerPartId=-1|Location.X=1208|Location.Y=320|Color=8388608|FontID=1|IsHidden=T|Text=125°C|Name=Max Operating Temperature
|RECORD=41|OwnerIndex=593|IndexInSheet=19|OwnerPartId=-1|Location.X=1208|Location.Y=320|Color=8388608|FontID=1|IsHidden=T|Text=2|Name=Number of Channels
|RECORD=41|OwnerIndex=593|IndexInSheet=20|OwnerPartId=-1|Location.X=1208|Location.Y=320|Color=8388608|FontID=1|IsHidden=T|Text=18R|Name=On-State Resistance
|RECORD=41|OwnerIndex=593|IndexInSheet=21|OwnerPartId=-1|Location.X=1208|Location.Y=320|Color=8388608|FontID=1|IsHidden=T|Text=Tape and Reel|Name=Packaging
|RECORD=34|OwnerIndex=593|IndexInSheet=-1|OwnerPartId=-1|Location.X=1230|Location.Y=320|Color=8388608|FontID=1|Text=U22|Name=Designator|ReadOnlyState=1
|RECORD=41|OwnerIndex=593|IndexInSheet=-1|OwnerPartId=1|Location.X=1230|Location.Y=140|Color=8388608|FontID=1|Text=TMUX1072RUTR|Name=Comment
|RECORD=44|OwnerIndex=593
|RECORD=45|OwnerIndex=630|IndexInSheet=-1|UseComponentLibrary=T|ModelName=FP-RUT0012A-MFG|ModelType=PCBLIB|DatafileCount=1|ModelDatafileEntity0=FP-RUT0012A-MFG|ModelDatafileKind0=PCBLib|IsCurrent=T|DatalinksLocked=T|DatabaseDatalinksLocked=T
|RECORD=46|OwnerIndex=631
|RECORD=48|OwnerIndex=631
|RECORD=17|IndexInSheet=54|OwnerPartId=-1|Style=4|ShowNetName=T|Location.X=1190|Location.Y=150|Orientation=3|Color=128|FontID=1|Text=GND
|RECORD=1|LibReference=b4654b650e69147ec39a6b967a45e02|ComponentDescription=General Purpose Ceramic Capacitor, 0402, 100nF, 10%, X7R, 15%, 25V|PartCount=2|DisplayModeCount=1|IndexInSheet=55|OwnerPartId=-1|Location.X=1150|Location.Y=340|CurrentPartId=1|LibraryPath=*|SourceLibraryName=Altium Content Vault|TargetFileName=*|AreaColor=11599871|Color=128|PartIDLocked=T|DesignItemId=CMP-2008-02519-2|AllPinCount=2
|RECORD=2|OwnerIndex=635|OwnerPartId=1|Electrical=4|PinConglomerate=49|PinLength=7|Location.X=1150|Location.Y=333|Name=1|Designator=1|PinPropagationDelay=0.000000E+000
|RECORD=2|OwnerIndex=635|OwnerPartId=1|Electrical=4|PinConglomerate=51|PinLength=6|Location.X=1150|Location.Y=326|Name=2|Designator=2|PinPropagationDelay=0.000000E+000
|RECORD=13|OwnerIndex=635|IsNotAccesible=T|IndexInSheet=2|OwnerPartId=1|Location.X=1160|Location.Y=333|Corner.X=1140|Corner.Y=333|LineWidth=1|Color=16711680
|RECORD=13|OwnerIndex=635|IsNotAccesible=T|IndexInSheet=3|OwnerPartId=1|Location.X=1160|Location.Y=327|Corner.X=1140|Corner.Y=327|LineWidth=1|Color=16711680
|RECORD=13|OwnerIndex=635|IsNotAccesible=T|IndexInSheet=4|OwnerPartId=1|Location.X=1150|Location.Y=333|Corner.X=1150|Corner.Y=336|LineWidth=1|Color=16711680
|RECORD=13|OwnerIndex=635|IsNotAccesible=T|IndexInSheet=5|OwnerPartId=1|Location.X=1150|Location.Y=326|Corner.X=1150|Corner.Y=325|LineWidth=1|Color=16711680
|RECORD=41|OwnerIndex=635|IndexInSheet=6|OwnerPartId=-1|Location.X=1139|Location.Y=342|Color=8388608|FontID=1|IsHidden=T|Text=1|Name=Package Quantity
|RECORD=41|OwnerIndex=635|IndexInSheet=7|OwnerPartId=-1|Location.X=1139|Location.Y=342|Color=8388608|FontID=1|IsHidden=T|Text=100nF|Name=Capacitance
|RECORD=41|OwnerIndex=635|IndexInSheet=8|OwnerPartId=-1|Location.X=1139|Location.Y=342|Color=8388608|FontID=1|IsHidden=T|Text=-55°C|Name=Min Operating Temperature
|RECORD=41|OwnerIndex=635|IndexInSheet=9|OwnerPartId=-1|Location.X=1139|Location.Y=342|Color=8388608|FontID=1|IsHidden=T|Text=25V|Name=Voltage
|RECORD=41|OwnerIndex=635|IndexInSheet=10|OwnerPartId=-1|Location.X=1139|Location.Y=342|Color=8388608|FontID=1|IsHidden=T|Text=25V|Name=Voltage Rating
|RECORD=41|OwnerIndex=635|IndexInSheet=11|OwnerPartId=-1|Location.X=1139|Location.Y=342|Color=8388608|FontID=1|IsHidden=T|Text=Flat|Name=Construction
|RECORD=41|OwnerIndex=635|IndexInSheet=12|OwnerPartId=-1|Location.X=1139|Location.Y=342|Color=8388608|FontID=1|IsHidden=T|Text=125°C|Name=Max Operating Temperature
|RECORD=41|OwnerIndex=635|IndexInSheet=13|OwnerPartId=-1|Location.X=1139|Location.Y=342|Color=8388608|FontID=1|IsHidden=T|Text=No|Name=Radiation Hardening
|RECORD=41|OwnerIndex=635|IndexInSheet=14|OwnerPartId=-1|Location.X=1139|Location.Y=342|Color=8388608|FontID=1|IsHidden=T|Text=0.5mm|Name=Depth
|RECORD=41|OwnerIndex=635|IndexInSheet=15|OwnerPartId=-1|Location.X=1139|Location.Y=342|Color=8388608|FontID=1|IsHidden=T|Text=0.022inch|Name=Thickness
|RECORD=41|OwnerIndex=635|IndexInSheet=16|OwnerPartId=-1|Location.X=1139|Location.Y=342|Color=8388608|FontID=1|IsHidden=T|Text=25V|Name=Voltage Rating (DC)
|RECORD=41|OwnerIndex=635|IndexInSheet=17|OwnerPartId=-1|Location.X=1139|Location.Y=342|Color=8388608|FontID=1|IsHidden=T|Text=2|Name=Number of Pins
|RECORD=41|OwnerIndex=635|IndexInSheet=18|OwnerPartId=-1|Location.X=1139|Location.Y=342|Color=8388608|FontID=1|IsHidden=T|Text=Lead Free|Name=Lead Free
|RECORD=41|OwnerIndex=635|IndexInSheet=19|OwnerPartId=-1|Location.X=1139|Location.Y=342|Color=8388608|FontID=1|IsHidden=T|Text=-|Name=Series
|RECORD=41|OwnerIndex=635|IndexInSheet=20|OwnerPartId=-1|Location.X=1139|Location.Y=342|Color=8388608|FontID=1|IsHidden=T|Text=No SVHC|Name=REACH SVHC
|RECORD=41|OwnerIndex=635|IndexInSheet=21|OwnerPartId=-1|Location.X=1139|Location.Y=342|Color=8388608|FontID=1|IsHidden=T|Text=1mm|Name=Length
|RECORD=41|OwnerIndex=635|IndexInSheet=22|OwnerPartId=-1|Location.X=1139|Location.Y=342|Color=8388608|FontID=1|IsHidden=T|Text=X7R|Name=Dielectric
|RECORD=41|OwnerIndex=635|IndexInSheet=23|OwnerPartId=-1|Location.X=1139|Location.Y=342|Color=8388608|FontID=1|IsHidden=T|Text=Yes|Name=RoHS Compliant
|RECORD=41|OwnerIndex=635|IndexInSheet=24|OwnerPartId=-1|Location.X=1139|Location.Y=342|Color=8388608|FontID=1|IsHidden=T|Text=Surface Mount|Name=Mount
|RECORD=41|OwnerIndex=635|IndexInSheet=25|OwnerPartId=-1|Location.X=1139|Location.Y=342|Color=8388608|FontID=1|IsHidden=T|Text=Tape and Reel|Name=Packaging
|RECORD=41|OwnerIndex=635|IndexInSheet=26|OwnerPartId=-1|Location.X=1139|Location.Y=342|Color=8388608|FontID=1|IsHidden=T|Text=0402|Name=Case/Package
|RECORD=41|OwnerIndex=635|IndexInSheet=27|OwnerPartId=-1|Location.X=1139|Location.Y=342|Color=8388608|FontID=1|IsHidden=T|Text=0402|Name=Case Code (Imperial)
|RECORD=41|OwnerIndex=635|IndexInSheet=28|OwnerPartId=-1|Location.X=1139|Location.Y=342|Color=8388608|FontID=1|IsHidden=T|Text=SMD/SMT|Name=Termination
|RECORD=41|OwnerIndex=635|IndexInSheet=29|OwnerPartId=-1|Location.X=1139|Location.Y=342|Color=8388608|FontID=1|IsHidden=T|Text=0.02inch|Name=Width
|RECORD=41|OwnerIndex=635|IndexInSheet=30|OwnerPartId=-1|Location.X=1139|Location.Y=342|Color=8388608|FontID=1|IsHidden=T|Text=1005|Name=Case Code (Metric)
|RECORD=41|OwnerIndex=635|IndexInSheet=31|OwnerPartId=-1|Location.X=1139|Location.Y=342|Color=8388608|FontID=1|IsHidden=T|Text=10%|Name=Tolerance
|RECORD=34|OwnerIndex=635|IndexInSheet=-1|OwnerPartId=-1|Location.X=1140|Location.Y=320|Orientation=1|Color=8388608|FontID=2|Text=C95|Name=Designator|ReadOnlyState=1
|RECORD=41|OwnerIndex=635|IndexInSheet=-1|OwnerPartId=1|Location.X=1170|Location.Y=305|Orientation=1|Color=8388608|FontID=2|Text=0.1uF_25V_0402|Name=Comment
|RECORD=44|OwnerIndex=635
|RECORD=45|OwnerIndex=672|IndexInSheet=-1|UseComponentLibrary=T|ModelName=FP-0402-L_1_0_1-W_0_5_0_1-IPC_C|ModelType=PCBLIB|DatafileCount=1|ModelDatafileEntity0=FP-0402-L_1_0_1-W_0_5_0_1-IPC_C|ModelDatafileKind0=PCBLib|IsCurrent=T|DatalinksLocked=T|DatabaseDatalinksLocked=T
|RECORD=46|OwnerIndex=673
|RECORD=48|OwnerIndex=673
|RECORD=45|OwnerIndex=672|IndexInSheet=-1|UseComponentLibrary=T|ModelName=FP-0402-L_1_0_1-W_0_5_0_1-IPC_B|ModelType=PCBLIB|DatafileCount=1|ModelDatafileEntity0=FP-0402-L_1_0_1-W_0_5_0_1-IPC_B|ModelDatafileKind0=PCBLib|DatalinksLocked=T|DatabaseDatalinksLocked=T
|RECORD=46|OwnerIndex=676
|RECORD=48|OwnerIndex=676
|RECORD=45|OwnerIndex=672|IndexInSheet=-1|UseComponentLibrary=T|ModelName=FP-0402-L_1_0_1-W_0_5_0_1-MFG|ModelType=PCBLIB|DatafileCount=1|ModelDatafileEntity0=FP-0402-L_1_0_1-W_0_5_0_1-MFG|ModelDatafileKind0=PCBLib|DatalinksLocked=T|DatabaseDatalinksLocked=T
|RECORD=46|OwnerIndex=679
|RECORD=48|OwnerIndex=679
|RECORD=45|OwnerIndex=672|IndexInSheet=-1|UseComponentLibrary=T|ModelName=FP-0402-L_1_0_1-W_0_5_0_1-IPC_A|ModelType=PCBLIB|DatafileCount=1|ModelDatafileEntity0=FP-0402-L_1_0_1-W_0_5_0_1-IPC_A|ModelDatafileKind0=PCBLib|DatalinksLocked=T|DatabaseDatalinksLocked=T
|RECORD=46|OwnerIndex=682
|RECORD=48|OwnerIndex=682
|RECORD=17|IndexInSheet=56|OwnerPartId=-1|ShowNetName=T|Location.X=1150|Location.Y=390|Orientation=1|Color=128|FontID=1|Text=GNSS2_P3V3
|RECORD=17|IndexInSheet=57|OwnerPartId=-1|Style=4|ShowNetName=T|Location.X=1150|Location.Y=310|Orientation=3|Color=128|FontID=1|Text=GND
|RECORD=4|IndexInSheet=58|OwnerPartId=-1|Location.X=1210|Location.Y=400|Color=8388608|FontID=1|Text=Select GPS Uart, either FTDI or FPGA
|RECORD=17|IndexInSheet=59|OwnerPartId=-1|ShowNetName=T|Location.X=1100|Location.Y=210|Orientation=2|Color=255|FontID=1|Text=DIP_SW_UART_SEL|IsCrossSheetConnector=T
|RECORD=17|IndexInSheet=60|OwnerPartId=-1|Style=4|ShowNetName=T|Location.X=1360|Location.Y=150|Orientation=3|Color=128|FontID=1|Text=GND
|RECORD=1|LibReference=RES|PartCount=2|DisplayModeCount=2|IndexInSheet=61|OwnerPartId=-1|Location.X=1080|Location.Y=300|CurrentPartId=1|SourceLibraryName=Altium Content Vault|TargetFileName=*|AreaColor=11599871|Color=128|PartIDLocked=F|DesignItemId=CMP-2002-08434-1|AllPinCount=2
|RECORD=2|OwnerIndex=690|OwnerPartId=1|OwnerPartDisplayMode=1|FormalType=1|Electrical=4|PinConglomerate=32|PinLength=10|Location.X=1100|Location.Y=290|Name=2|Designator=2|PinPropagationDelay=0.000000E+000
|RECORD=2|OwnerIndex=690|OwnerPartId=1|OwnerPartDisplayMode=1|FormalType=1|Electrical=4|PinConglomerate=34|PinLength=10|Location.X=1080|Location.Y=290|Name=1|Designator=1|PinPropagationDelay=0.000000E+000
|RECORD=14|OwnerIndex=690|IsNotAccesible=T|IndexInSheet=2|OwnerPartId=1|OwnerPartDisplayMode=1|Location.X=1080|Location.Y=286|Corner.X=1100|Corner.Y=294|LineWidth=1|Color=16711680|AreaColor=11599871
|RECORD=2|OwnerIndex=690|OwnerPartId=1|FormalType=1|Electrical=4|PinConglomerate=32|PinLength=10|Location.X=1100|Location.Y=290|Name=2|Designator=2|PinPropagationDelay=0.000000E+000
|RECORD=2|OwnerIndex=690|OwnerPartId=1|FormalType=1|Electrical=4|PinConglomerate=34|PinLength=10|Location.X=1080|Location.Y=290|Name=1|Designator=1|PinPropagationDelay=0.000000E+000
|RECORD=6|OwnerIndex=690|IsNotAccesible=T|IndexInSheet=5|OwnerPartId=1|LineWidth=1|Color=16711680|LocationCount=10|X1=1100|Y1=290|X2=1096|Y2=290|X3=1095|Y3=288|X4=1093|Y4=292|X5=1091|Y5=288|X6=1089|Y6=292|X7=1087|Y7=288|X8=1085|Y8=292|X9=1084|Y9=290|X10=1080|Y10=290
|RECORD=41|OwnerIndex=690|IndexInSheet=6|OwnerPartId=-1|Location.X=1068|Location.Y=303|Color=8388608|FontID=1|IsHidden=T|Text=CRCW040227R0FKED|Name=Part Number
|RECORD=41|OwnerIndex=690|IndexInSheet=7|OwnerPartId=-1|Location.X=1068|Location.Y=303|Color=8388608|FontID=1|IsHidden=T|Text=Vishay Dale|Name=Manufacturer
|RECORD=34|OwnerIndex=690|IndexInSheet=-1|OwnerPartId=-1|Location.X=1060|Location.Y=290|Color=8388608|FontID=1|Text=R90|Name=Designator|ReadOnlyState=1
|RECORD=41|OwnerIndex=690|IndexInSheet=-1|OwnerPartId=-1|Location.X=1080|Location.Y=290|Color=8388608|FontID=1|Text=27_1%_0402|Name=Comment
|RECORD=44|OwnerIndex=690
|RECORD=45|OwnerIndex=705|IndexInSheet=-1|Description=Chip Resistor, 2-Leads, Body 1.00x0.50mm, IPC Medium Density|UseComponentLibrary=T|ModelName=RESC1005X40X25NL05T05|ModelType=PCBLIB|DatafileCount=1|ModelDatafileEntity0=RESC1005X40X25NL05T05|ModelDatafileKind0=PCBLib|IsCurrent=T|DatalinksLocked=T|DatabaseDatalinksLocked=T
|RECORD=46|OwnerIndex=706
|RECORD=48|OwnerIndex=706
|RECORD=41|OwnerIndex=708|IndexInSheet=-1|OwnerPartId=-1|Color=8388608|FontID=1|IsHidden=T|Text=2D|Name=Available Preview Images
|RECORD=45|OwnerIndex=705|IndexInSheet=-1|Description=Chip Resistor, 2-Leads, Body 1.00x0.50mm, IPC High Density|UseComponentLibrary=T|ModelName=RESC1005X40X25LL05T05|ModelType=PCBLIB|DatafileCount=1|ModelDatafileEntity0=RESC1005X40X25LL05T05|ModelDatafileKind0=PCBLib|DatalinksLocked=T|DatabaseDatalinksLocked=T
|RECORD=46|OwnerIndex=710
|RECORD=48|OwnerIndex=710
|RECORD=41|OwnerIndex=712|IndexInSheet=-1|OwnerPartId=-1|Color=8388608|FontID=1|IsHidden=T|Text=2D|Name=Available Preview Images
|RECORD=45|OwnerIndex=705|IndexInSheet=-1|Description=Chip Resistor, 2-Leads, Body 1.00x0.50mm, IPC Low Density|UseComponentLibrary=T|ModelName=RESC1005X40X25ML05T05|ModelType=PCBLIB|DatafileCount=1|ModelDatafileEntity0=RESC1005X40X25ML05T05|ModelDatafileKind0=PCBLib|DatalinksLocked=T|DatabaseDatalinksLocked=T
|RECORD=46|OwnerIndex=714
|RECORD=48|OwnerIndex=714
|RECORD=41|OwnerIndex=716|IndexInSheet=-1|OwnerPartId=-1|Color=8388608|FontID=1|IsHidden=T|Text=2D|Name=Available Preview Images
|RECORD=1|LibReference=RES|PartCount=2|DisplayModeCount=2|IndexInSheet=62|OwnerPartId=-1|Location.X=1080|Location.Y=260|CurrentPartId=1|SourceLibraryName=Altium Content Vault|TargetFileName=*|AreaColor=11599871|Color=128|PartIDLocked=F|DesignItemId=CMP-2002-08434-1|AllPinCount=2
|RECORD=2|OwnerIndex=718|OwnerPartId=1|OwnerPartDisplayMode=1|FormalType=1|Electrical=4|PinConglomerate=32|PinLength=10|Location.X=1100|Location.Y=250|Name=2|Designator=2|PinPropagationDelay=0.000000E+000
|RECORD=2|OwnerIndex=718|OwnerPartId=1|OwnerPartDisplayMode=1|FormalType=1|Electrical=4|PinConglomerate=34|PinLength=10|Location.X=1080|Location.Y=250|Name=1|Designator=1|PinPropagationDelay=0.000000E+000
|RECORD=14|OwnerIndex=718|IsNotAccesible=T|IndexInSheet=2|OwnerPartId=1|OwnerPartDisplayMode=1|Location.X=1080|Location.Y=246|Corner.X=1100|Corner.Y=254|LineWidth=1|Color=16711680|AreaColor=11599871
|RECORD=2|OwnerIndex=718|OwnerPartId=1|FormalType=1|Electrical=4|PinConglomerate=32|PinLength=10|Location.X=1100|Location.Y=250|Name=2|Designator=2|PinPropagationDelay=0.000000E+000
|RECORD=2|OwnerIndex=718|OwnerPartId=1|FormalType=1|Electrical=4|PinConglomerate=34|PinLength=10|Location.X=1080|Location.Y=250|Name=1|Designator=1|PinPropagationDelay=0.000000E+000
|RECORD=6|OwnerIndex=718|IsNotAccesible=T|IndexInSheet=5|OwnerPartId=1|LineWidth=1|Color=16711680|LocationCount=10|X1=1100|Y1=250|X2=1096|Y2=250|X3=1095|Y3=248|X4=1093|Y4=252|X5=1091|Y5=248|X6=1089|Y6=252|X7=1087|Y7=248|X8=1085|Y8=252|X9=1084|Y9=250|X10=1080|Y10=250
|RECORD=41|OwnerIndex=718|IndexInSheet=6|OwnerPartId=-1|Location.X=1068|Location.Y=263|Color=8388608|FontID=1|IsHidden=T|Text=CRCW040227R0FKED|Name=Part Number
|RECORD=41|OwnerIndex=718|IndexInSheet=7|OwnerPartId=-1|Location.X=1068|Location.Y=263|Color=8388608|FontID=1|IsHidden=T|Text=Vishay Dale|Name=Manufacturer
|RECORD=34|OwnerIndex=718|IndexInSheet=-1|OwnerPartId=-1|Location.X=1060|Location.Y=250|Color=8388608|FontID=1|Text=R92|Name=Designator|ReadOnlyState=1
|RECORD=41|OwnerIndex=718|IndexInSheet=-1|OwnerPartId=-1|Location.X=1080|Location.Y=250|Color=8388608|FontID=1|Text=27_1%_0402|Name=Comment
|RECORD=44|OwnerIndex=718
|RECORD=45|OwnerIndex=733|IndexInSheet=-1|Description=Chip Resistor, 2-Leads, Body 1.00x0.50mm, IPC Medium Density|UseComponentLibrary=T|ModelName=RESC1005X40X25NL05T05|ModelType=PCBLIB|DatafileCount=1|ModelDatafileEntity0=RESC1005X40X25NL05T05|ModelDatafileKind0=PCBLib|IsCurrent=T|DatalinksLocked=T|DatabaseDatalinksLocked=T
|RECORD=46|OwnerIndex=734
|RECORD=48|OwnerIndex=734
|RECORD=41|OwnerIndex=736|IndexInSheet=-1|OwnerPartId=-1|Color=8388608|FontID=1|IsHidden=T|Text=2D|Name=Available Preview Images
|RECORD=45|OwnerIndex=733|IndexInSheet=-1|Description=Chip Resistor, 2-Leads, Body 1.00x0.50mm, IPC High Density|UseComponentLibrary=T|ModelName=RESC1005X40X25LL05T05|ModelType=PCBLIB|DatafileCount=1|ModelDatafileEntity0=RESC1005X40X25LL05T05|ModelDatafileKind0=PCBLib|DatalinksLocked=T|DatabaseDatalinksLocked=T
|RECORD=46|OwnerIndex=738
|RECORD=48|OwnerIndex=738
|RECORD=41|OwnerIndex=740|IndexInSheet=-1|OwnerPartId=-1|Color=8388608|FontID=1|IsHidden=T|Text=2D|Name=Available Preview Images
|RECORD=45|OwnerIndex=733|IndexInSheet=-1|Description=Chip Resistor, 2-Leads, Body 1.00x0.50mm, IPC Low Density|UseComponentLibrary=T|ModelName=RESC1005X40X25ML05T05|ModelType=PCBLIB|DatafileCount=1|ModelDatafileEntity0=RESC1005X40X25ML05T05|ModelDatafileKind0=PCBLib|DatalinksLocked=T|DatabaseDatalinksLocked=T
|RECORD=46|OwnerIndex=742
|RECORD=48|OwnerIndex=742
|RECORD=41|OwnerIndex=744|IndexInSheet=-1|OwnerPartId=-1|Color=8388608|FontID=1|IsHidden=T|Text=2D|Name=Available Preview Images
|RECORD=17|IndexInSheet=63|OwnerPartId=-1|ShowNetName=T|Location.X=1030|Location.Y=230|Orientation=2|Color=255|FontID=1|Text=GPS2_RX_FPGA|IsCrossSheetConnector=T
|RECORD=17|IndexInSheet=64|OwnerPartId=-1|ShowNetName=T|Location.X=1030|Location.Y=270|Orientation=2|Color=255|FontID=1|Text=GPS2_TX_FPGA|IsCrossSheetConnector=T
|RECORD=17|IndexInSheet=65|OwnerPartId=-1|ShowNetName=T|Location.X=1030|Location.Y=250|Orientation=2|Color=255|FontID=1|Text=FTDI_TX|IsCrossSheetConnector=T
|RECORD=17|IndexInSheet=66|OwnerPartId=-1|Style=1|ShowNetName=T|Location.X=1030|Location.Y=290|Orientation=2|Color=255|FontID=1|Text=FTDI_RX|IsCrossSheetConnector=T
|RECORD=17|IndexInSheet=67|OwnerPartId=-1|Style=1|ShowNetName=T|Location.X=1420|Location.Y=250|Color=255|FontID=1|Text=GPS2_RX|IsCrossSheetConnector=T
|RECORD=17|IndexInSheet=68|OwnerPartId=-1|ShowNetName=T|Location.X=1420|Location.Y=290|Color=255|FontID=1|Text=GPS2_TX|IsCrossSheetConnector=T
|RECORD=1|LibReference=RES|PartCount=2|DisplayModeCount=2|IndexInSheet=69|OwnerPartId=-1|Location.X=1080|Location.Y=240|CurrentPartId=1|SourceLibraryName=Altium Content Vault|TargetFileName=*|AreaColor=11599871|Color=128|PartIDLocked=F|DesignItemId=CMP-2002-08434-1|AllPinCount=2
|RECORD=2|OwnerIndex=752|OwnerPartId=1|OwnerPartDisplayMode=1|FormalType=1|Electrical=4|PinConglomerate=32|PinLength=10|Location.X=1100|Location.Y=230|Name=2|Designator=2|PinPropagationDelay=0.000000E+000
|RECORD=2|OwnerIndex=752|OwnerPartId=1|OwnerPartDisplayMode=1|FormalType=1|Electrical=4|PinConglomerate=34|PinLength=10|Location.X=1080|Location.Y=230|Name=1|Designator=1|PinPropagationDelay=0.000000E+000
|RECORD=14|OwnerIndex=752|IsNotAccesible=T|IndexInSheet=2|OwnerPartId=1|OwnerPartDisplayMode=1|Location.X=1080|Location.Y=226|Corner.X=1100|Corner.Y=234|LineWidth=1|Color=16711680|AreaColor=11599871
|RECORD=2|OwnerIndex=752|OwnerPartId=1|FormalType=1|Electrical=4|PinConglomerate=32|PinLength=10|Location.X=1100|Location.Y=230|Name=2|Designator=2|PinPropagationDelay=0.000000E+000
|RECORD=2|OwnerIndex=752|OwnerPartId=1|FormalType=1|Electrical=4|PinConglomerate=34|PinLength=10|Location.X=1080|Location.Y=230|Name=1|Designator=1|PinPropagationDelay=0.000000E+000
|RECORD=6|OwnerIndex=752|IsNotAccesible=T|IndexInSheet=5|OwnerPartId=1|LineWidth=1|Color=16711680|LocationCount=10|X1=1100|Y1=230|X2=1096|Y2=230|X3=1095|Y3=228|X4=1093|Y4=232|X5=1091|Y5=228|X6=1089|Y6=232|X7=1087|Y7=228|X8=1085|Y8=232|X9=1084|Y9=230|X10=1080|Y10=230
|RECORD=41|OwnerIndex=752|IndexInSheet=6|OwnerPartId=-1|Location.X=1068|Location.Y=243|Color=8388608|FontID=1|IsHidden=T|Text=CRCW040227R0FKED|Name=Part Number
|RECORD=41|OwnerIndex=752|IndexInSheet=7|OwnerPartId=-1|Location.X=1068|Location.Y=243|Color=8388608|FontID=1|IsHidden=T|Text=Vishay Dale|Name=Manufacturer
|RECORD=34|OwnerIndex=752|IndexInSheet=-1|OwnerPartId=-1|Location.X=1060|Location.Y=230|Color=8388608|FontID=1|Text=R93|Name=Designator|ReadOnlyState=1
|RECORD=41|OwnerIndex=752|IndexInSheet=-1|OwnerPartId=-1|Location.X=1080|Location.Y=230|Color=8388608|FontID=1|Text=27_1%_0402|Name=Comment
|RECORD=44|OwnerIndex=752
|RECORD=45|OwnerIndex=767|IndexInSheet=-1|Description=Chip Resistor, 2-Leads, Body 1.00x0.50mm, IPC Medium Density|UseComponentLibrary=T|ModelName=RESC1005X40X25NL05T05|ModelType=PCBLIB|DatafileCount=1|ModelDatafileEntity0=RESC1005X40X25NL05T05|ModelDatafileKind0=PCBLib|IsCurrent=T|DatalinksLocked=T|DatabaseDatalinksLocked=T
|RECORD=46|OwnerIndex=768
|RECORD=48|OwnerIndex=768
|RECORD=41|OwnerIndex=770|IndexInSheet=-1|OwnerPartId=-1|Color=8388608|FontID=1|IsHidden=T|Text=2D|Name=Available Preview Images
|RECORD=45|OwnerIndex=767|IndexInSheet=-1|Description=Chip Resistor, 2-Leads, Body 1.00x0.50mm, IPC High Density|UseComponentLibrary=T|ModelName=RESC1005X40X25LL05T05|ModelType=PCBLIB|DatafileCount=1|ModelDatafileEntity0=RESC1005X40X25LL05T05|ModelDatafileKind0=PCBLib|DatalinksLocked=T|DatabaseDatalinksLocked=T
|RECORD=46|OwnerIndex=772
|RECORD=48|OwnerIndex=772
|RECORD=41|OwnerIndex=774|IndexInSheet=-1|OwnerPartId=-1|Color=8388608|FontID=1|IsHidden=T|Text=2D|Name=Available Preview Images
|RECORD=45|OwnerIndex=767|IndexInSheet=-1|Description=Chip Resistor, 2-Leads, Body 1.00x0.50mm, IPC Low Density|UseComponentLibrary=T|ModelName=RESC1005X40X25ML05T05|ModelType=PCBLIB|DatafileCount=1|ModelDatafileEntity0=RESC1005X40X25ML05T05|ModelDatafileKind0=PCBLib|DatalinksLocked=T|DatabaseDatalinksLocked=T
|RECORD=46|OwnerIndex=776
|RECORD=48|OwnerIndex=776
|RECORD=41|OwnerIndex=778|IndexInSheet=-1|OwnerPartId=-1|Color=8388608|FontID=1|IsHidden=T|Text=2D|Name=Available Preview Images
|RECORD=1|LibReference=RES|PartCount=2|DisplayModeCount=2|IndexInSheet=70|OwnerPartId=-1|Location.X=1080|Location.Y=280|CurrentPartId=1|SourceLibraryName=Altium Content Vault|TargetFileName=*|AreaColor=11599871|Color=128|PartIDLocked=F|DesignItemId=CMP-2002-08434-1|AllPinCount=2
|RECORD=2|OwnerIndex=780|OwnerPartId=1|OwnerPartDisplayMode=1|FormalType=1|Electrical=4|PinConglomerate=32|PinLength=10|Location.X=1100|Location.Y=270|Name=2|Designator=2|PinPropagationDelay=0.000000E+000
|RECORD=2|OwnerIndex=780|OwnerPartId=1|OwnerPartDisplayMode=1|FormalType=1|Electrical=4|PinConglomerate=34|PinLength=10|Location.X=1080|Location.Y=270|Name=1|Designator=1|PinPropagationDelay=0.000000E+000
|RECORD=14|OwnerIndex=780|IsNotAccesible=T|IndexInSheet=2|OwnerPartId=1|OwnerPartDisplayMode=1|Location.X=1080|Location.Y=266|Corner.X=1100|Corner.Y=274|LineWidth=1|Color=16711680|AreaColor=11599871
|RECORD=2|OwnerIndex=780|OwnerPartId=1|FormalType=1|Electrical=4|PinConglomerate=32|PinLength=10|Location.X=1100|Location.Y=270|Name=2|Designator=2|PinPropagationDelay=0.000000E+000
|RECORD=2|OwnerIndex=780|OwnerPartId=1|FormalType=1|Electrical=4|PinConglomerate=34|PinLength=10|Location.X=1080|Location.Y=270|Name=1|Designator=1|PinPropagationDelay=0.000000E+000
|RECORD=6|OwnerIndex=780|IsNotAccesible=T|IndexInSheet=5|OwnerPartId=1|LineWidth=1|Color=16711680|LocationCount=10|X1=1100|Y1=270|X2=1096|Y2=270|X3=1095|Y3=268|X4=1093|Y4=272|X5=1091|Y5=268|X6=1089|Y6=272|X7=1087|Y7=268|X8=1085|Y8=272|X9=1084|Y9=270|X10=1080|Y10=270
|RECORD=41|OwnerIndex=780|IndexInSheet=6|OwnerPartId=-1|Location.X=1068|Location.Y=283|Color=8388608|FontID=1|IsHidden=T|Text=CRCW040227R0FKED|Name=Part Number
|RECORD=41|OwnerIndex=780|IndexInSheet=7|OwnerPartId=-1|Location.X=1068|Location.Y=283|Color=8388608|FontID=1|IsHidden=T|Text=Vishay Dale|Name=Manufacturer
|RECORD=34|OwnerIndex=780|IndexInSheet=-1|OwnerPartId=-1|Location.X=1060|Location.Y=270|Color=8388608|FontID=1|Text=R91|Name=Designator|ReadOnlyState=1
|RECORD=41|OwnerIndex=780|IndexInSheet=-1|OwnerPartId=-1|Location.X=1080|Location.Y=270|Color=8388608|FontID=1|Text=27_1%_0402|Name=Comment
|RECORD=44|OwnerIndex=780
|RECORD=45|OwnerIndex=795|IndexInSheet=-1|Description=Chip Resistor, 2-Leads, Body 1.00x0.50mm, IPC Medium Density|UseComponentLibrary=T|ModelName=RESC1005X40X25NL05T05|ModelType=PCBLIB|DatafileCount=1|ModelDatafileEntity0=RESC1005X40X25NL05T05|ModelDatafileKind0=PCBLib|IsCurrent=T|DatalinksLocked=T|DatabaseDatalinksLocked=T
|RECORD=46|OwnerIndex=796
|RECORD=48|OwnerIndex=796
|RECORD=41|OwnerIndex=798|IndexInSheet=-1|OwnerPartId=-1|Color=8388608|FontID=1|IsHidden=T|Text=2D|Name=Available Preview Images
|RECORD=45|OwnerIndex=795|IndexInSheet=-1|Description=Chip Resistor, 2-Leads, Body 1.00x0.50mm, IPC High Density|UseComponentLibrary=T|ModelName=RESC1005X40X25LL05T05|ModelType=PCBLIB|DatafileCount=1|ModelDatafileEntity0=RESC1005X40X25LL05T05|ModelDatafileKind0=PCBLib|DatalinksLocked=T|DatabaseDatalinksLocked=T
|RECORD=46|OwnerIndex=800
|RECORD=48|OwnerIndex=800
|RECORD=41|OwnerIndex=802|IndexInSheet=-1|OwnerPartId=-1|Color=8388608|FontID=1|IsHidden=T|Text=2D|Name=Available Preview Images
|RECORD=45|OwnerIndex=795|IndexInSheet=-1|Description=Chip Resistor, 2-Leads, Body 1.00x0.50mm, IPC Low Density|UseComponentLibrary=T|ModelName=RESC1005X40X25ML05T05|ModelType=PCBLIB|DatafileCount=1|ModelDatafileEntity0=RESC1005X40X25ML05T05|ModelDatafileKind0=PCBLib|DatalinksLocked=T|DatabaseDatalinksLocked=T
|RECORD=46|OwnerIndex=804
|RECORD=48|OwnerIndex=804
|RECORD=41|OwnerIndex=806|IndexInSheet=-1|OwnerPartId=-1|Color=8388608|FontID=1|IsHidden=T|Text=2D|Name=Available Preview Images
|RECORD=1|LibReference=12a319ab100cd6cfe745e35972674f5|ComponentDescription=IC SWITCH SPDT DUAL 12UQFN|PartCount=2|DisplayModeCount=1|IndexInSheet=71|OwnerPartId=-1|Location.X=1200|Location.Y=790|CurrentPartId=1|LibraryPath=*|SourceLibraryName=Altium Content Vault|TargetFileName=*|AreaColor=11599871|Color=128|PartIDLocked=T|DesignItemId=CMP-04892-000114-1|AllPinCount=12
|RECORD=14|OwnerIndex=808|IsNotAccesible=T|OwnerPartId=1|Location.X=1220|Location.Y=630|Corner.X=1320|Corner.Y=800|LineWidth=1|Color=128|AreaColor=11599871|IsSolid=T
|RECORD=2|OwnerIndex=808|OwnerPartId=1|Electrical=7|PinConglomerate=58|PinLength=20|Location.X=1220|Location.Y=790|Name=VCC|Designator=9|PinName_PositionConglomerate=16|Name_CustomFontID=1|PinDesignator_PositionConglomerate=16|Designator_CustomFontID=1|PinPropagationDelay=0.000000E+000
|RECORD=2|OwnerIndex=808|OwnerPartId=1|PinConglomerate=58|PinLength=20|Location.X=1220|Location.Y=690|Name=SEL1|Designator=1|PinName_PositionConglomerate=16|Name_CustomFontID=1|PinDesignator_PositionConglomerate=16|Designator_CustomFontID=1|PinPropagationDelay=0.000000E+000
|RECORD=2|OwnerIndex=808|OwnerPartId=1|PinConglomerate=58|PinLength=20|Location.X=1220|Location.Y=680|Name=SEL2|Designator=5|PinName_PositionConglomerate=16|Name_CustomFontID=1|PinDesignator_PositionConglomerate=16|Designator_CustomFontID=1|PinPropagationDelay=0.000000E+000
|RECORD=2|OwnerIndex=808|OwnerPartId=1|Electrical=4|PinConglomerate=58|PinLength=20|Location.X=1220|Location.Y=750|Name=NO1|Designator=2|PinName_PositionConglomerate=16|Name_CustomFontID=1|PinDesignator_PositionConglomerate=16|Designator_CustomFontID=1|PinPropagationDelay=0.000000E+000
|RECORD=2|OwnerIndex=808|OwnerPartId=1|Electrical=4|PinConglomerate=58|PinLength=20|Location.X=1220|Location.Y=710|Name=NO2|Designator=4|PinName_PositionConglomerate=16|Name_CustomFontID=1|PinDesignator_PositionConglomerate=16|Designator_CustomFontID=1|PinPropagationDelay=0.000000E+000
|RECORD=2|OwnerIndex=808|OwnerPartId=1|Electrical=4|PinConglomerate=56|PinLength=20|Location.X=1320|Location.Y=770|Name=COM1|Designator=11|PinName_PositionConglomerate=16|Name_CustomFontID=1|PinDesignator_PositionConglomerate=16|Designator_CustomFontID=1|PinPropagationDelay=0.000000E+000
|RECORD=2|OwnerIndex=808|OwnerPartId=1|Electrical=4|PinConglomerate=56|PinLength=20|Location.X=1320|Location.Y=730|Name=COM2|Designator=7|PinName_PositionConglomerate=16|Name_CustomFontID=1|PinDesignator_PositionConglomerate=16|Designator_CustomFontID=1|PinPropagationDelay=0.000000E+000
|RECORD=2|OwnerIndex=808|OwnerPartId=1|Electrical=3|PinConglomerate=58|PinLength=20|Location.X=1220|Location.Y=640|Name=F\L\T\|Designator=12|PinName_PositionConglomerate=16|Name_CustomFontID=1|PinDesignator_PositionConglomerate=16|Designator_CustomFontID=1|PinPropagationDelay=0.000000E+000
|RECORD=2|OwnerIndex=808|OwnerPartId=1|PinConglomerate=58|PinLength=20|Location.X=1220|Location.Y=660|Name=O\E\|Designator=6|PinName_PositionConglomerate=16|Name_CustomFontID=1|PinDesignator_PositionConglomerate=16|Designator_CustomFontID=1|PinPropagationDelay=0.000000E+000
|RECORD=2|OwnerIndex=808|OwnerPartId=1|Electrical=4|PinConglomerate=58|PinLength=20|Location.X=1220|Location.Y=770|Name=NC1|Designator=10|PinName_PositionConglomerate=16|Name_CustomFontID=1|PinDesignator_PositionConglomerate=16|Designator_CustomFontID=1|PinPropagationDelay=0.000000E+000
|RECORD=2|OwnerIndex=808|OwnerPartId=1|Electrical=4|PinConglomerate=58|PinLength=20|Location.X=1220|Location.Y=730|Name=NC2|Designator=8|PinName_PositionConglomerate=16|Name_CustomFontID=1|PinDesignator_PositionConglomerate=16|Designator_CustomFontID=1|PinPropagationDelay=0.000000E+000
|RECORD=2|OwnerIndex=808|OwnerPartId=1|Electrical=7|PinConglomerate=56|PinLength=20|Location.X=1320|Location.Y=640|Name=GND|Designator=3|PinName_PositionConglomerate=16|Name_CustomFontID=1|PinDesignator_PositionConglomerate=16|Designator_CustomFontID=1|PinPropagationDelay=0.000000E+000
|RECORD=41|OwnerIndex=808|IndexInSheet=13|OwnerPartId=-1|Location.X=1198|Location.Y=800|Color=8388608|FontID=1|IsHidden=T|Text=12|Name=Number of Pins
|RECORD=41|OwnerIndex=808|IndexInSheet=14|OwnerPartId=-1|Location.X=1198|Location.Y=800|Color=8388608|FontID=1|IsHidden=T|Text=2|Name=Number of Circuits
|RECORD=41|OwnerIndex=808|IndexInSheet=15|OwnerPartId=-1|Location.X=1198|Location.Y=800|Color=8388608|FontID=1|IsHidden=T|Text=-40°C|Name=Min Operating Temperature
|RECORD=41|OwnerIndex=808|IndexInSheet=16|OwnerPartId=-1|Location.X=1198|Location.Y=800|Color=8388608|FontID=1|IsHidden=T|Text=Yes|Name=RoHS Compliant
|RECORD=41|OwnerIndex=808|IndexInSheet=17|OwnerPartId=-1|Location.X=1198|Location.Y=800|Color=8388608|FontID=1|IsHidden=T|Text=1.2GHz|Name=-3db Bandwidth
|RECORD=41|OwnerIndex=808|IndexInSheet=18|OwnerPartId=-1|Location.X=1198|Location.Y=800|Color=8388608|FontID=1|IsHidden=T|Text=125°C|Name=Max Operating Temperature
|RECORD=41|OwnerIndex=808|IndexInSheet=19|OwnerPartId=-1|Location.X=1198|Location.Y=800|Color=8388608|FontID=1|IsHidden=T|Text=2|Name=Number of Channels
|RECORD=41|OwnerIndex=808|IndexInSheet=20|OwnerPartId=-1|Location.X=1198|Location.Y=800|Color=8388608|FontID=1|IsHidden=T|Text=18R|Name=On-State Resistance
|RECORD=41|OwnerIndex=808|IndexInSheet=21|OwnerPartId=-1|Location.X=1198|Location.Y=800|Color=8388608|FontID=1|IsHidden=T|Text=Tape and Reel|Name=Packaging
|RECORD=34|OwnerIndex=808|IndexInSheet=-1|OwnerPartId=-1|Location.X=1220|Location.Y=800|Color=8388608|FontID=1|Text=U21|Name=Designator|ReadOnlyState=1
|RECORD=41|OwnerIndex=808|IndexInSheet=-1|OwnerPartId=1|Location.X=1220|Location.Y=620|Color=8388608|FontID=1|Text=TMUX1072RUTR|Name=Comment
|RECORD=44|OwnerIndex=808
|RECORD=45|OwnerIndex=845|IndexInSheet=-1|UseComponentLibrary=T|ModelName=FP-RUT0012A-MFG|ModelType=PCBLIB|DatafileCount=1|ModelDatafileEntity0=FP-RUT0012A-MFG|ModelDatafileKind0=PCBLib|IsCurrent=T|DatalinksLocked=T|DatabaseDatalinksLocked=T
|RECORD=46|OwnerIndex=846
|RECORD=48|OwnerIndex=846
|RECORD=17|IndexInSheet=72|OwnerPartId=-1|Style=4|ShowNetName=T|Location.X=1180|Location.Y=630|Orientation=3|Color=128|FontID=1|Text=GND
|RECORD=1|LibReference=b4654b650e69147ec39a6b967a45e02|ComponentDescription=General Purpose Ceramic Capacitor, 0402, 100nF, 10%, X7R, 15%, 25V|PartCount=2|DisplayModeCount=1|IndexInSheet=73|OwnerPartId=-1|Location.X=1140|Location.Y=820|CurrentPartId=1|LibraryPath=*|SourceLibraryName=Altium Content Vault|TargetFileName=*|AreaColor=11599871|Color=128|PartIDLocked=T|DesignItemId=CMP-2008-02519-2|AllPinCount=2
|RECORD=2|OwnerIndex=850|OwnerPartId=1|Electrical=4|PinConglomerate=49|PinLength=7|Location.X=1140|Location.Y=813|Name=1|Designator=1|PinPropagationDelay=0.000000E+000
|RECORD=2|OwnerIndex=850|OwnerPartId=1|Electrical=4|PinConglomerate=51|PinLength=6|Location.X=1140|Location.Y=806|Name=2|Designator=2|PinPropagationDelay=0.000000E+000
|RECORD=13|OwnerIndex=850|IsNotAccesible=T|IndexInSheet=2|OwnerPartId=1|Location.X=1150|Location.Y=813|Corner.X=1130|Corner.Y=813|LineWidth=1|Color=16711680
|RECORD=13|OwnerIndex=850|IsNotAccesible=T|IndexInSheet=3|OwnerPartId=1|Location.X=1150|Location.Y=807|Corner.X=1130|Corner.Y=807|LineWidth=1|Color=16711680
|RECORD=13|OwnerIndex=850|IsNotAccesible=T|IndexInSheet=4|OwnerPartId=1|Location.X=1140|Location.Y=813|Corner.X=1140|Corner.Y=816|LineWidth=1|Color=16711680
|RECORD=13|OwnerIndex=850|IsNotAccesible=T|IndexInSheet=5|OwnerPartId=1|Location.X=1140|Location.Y=806|Corner.X=1140|Corner.Y=805|LineWidth=1|Color=16711680
|RECORD=41|OwnerIndex=850|IndexInSheet=6|OwnerPartId=-1|Location.X=1129|Location.Y=822|Color=8388608|FontID=1|IsHidden=T|Text=1|Name=Package Quantity
|RECORD=41|OwnerIndex=850|IndexInSheet=7|OwnerPartId=-1|Location.X=1129|Location.Y=822|Color=8388608|FontID=1|IsHidden=T|Text=100nF|Name=Capacitance
|RECORD=41|OwnerIndex=850|IndexInSheet=8|OwnerPartId=-1|Location.X=1129|Location.Y=822|Color=8388608|FontID=1|IsHidden=T|Text=-55°C|Name=Min Operating Temperature
|RECORD=41|OwnerIndex=850|IndexInSheet=9|OwnerPartId=-1|Location.X=1129|Location.Y=822|Color=8388608|FontID=1|IsHidden=T|Text=25V|Name=Voltage
|RECORD=41|OwnerIndex=850|IndexInSheet=10|OwnerPartId=-1|Location.X=1129|Location.Y=822|Color=8388608|FontID=1|IsHidden=T|Text=25V|Name=Voltage Rating
|RECORD=41|OwnerIndex=850|IndexInSheet=11|OwnerPartId=-1|Location.X=1129|Location.Y=822|Color=8388608|FontID=1|IsHidden=T|Text=Flat|Name=Construction
|RECORD=41|OwnerIndex=850|IndexInSheet=12|OwnerPartId=-1|Location.X=1129|Location.Y=822|Color=8388608|FontID=1|IsHidden=T|Text=125°C|Name=Max Operating Temperature
|RECORD=41|OwnerIndex=850|IndexInSheet=13|OwnerPartId=-1|Location.X=1129|Location.Y=822|Color=8388608|FontID=1|IsHidden=T|Text=No|Name=Radiation Hardening
|RECORD=41|OwnerIndex=850|IndexInSheet=14|OwnerPartId=-1|Location.X=1129|Location.Y=822|Color=8388608|FontID=1|IsHidden=T|Text=0.5mm|Name=Depth
|RECORD=41|OwnerIndex=850|IndexInSheet=15|OwnerPartId=-1|Location.X=1129|Location.Y=822|Color=8388608|FontID=1|IsHidden=T|Text=0.022inch|Name=Thickness
|RECORD=41|OwnerIndex=850|IndexInSheet=16|OwnerPartId=-1|Location.X=1129|Location.Y=822|Color=8388608|FontID=1|IsHidden=T|Text=25V|Name=Voltage Rating (DC)
|RECORD=41|OwnerIndex=850|IndexInSheet=17|OwnerPartId=-1|Location.X=1129|Location.Y=822|Color=8388608|FontID=1|IsHidden=T|Text=2|Name=Number of Pins
|RECORD=41|OwnerIndex=850|IndexInSheet=18|OwnerPartId=-1|Location.X=1129|Location.Y=822|Color=8388608|FontID=1|IsHidden=T|Text=Lead Free|Name=Lead Free
|RECORD=41|OwnerIndex=850|IndexInSheet=19|OwnerPartId=-1|Location.X=1129|Location.Y=822|Color=8388608|FontID=1|IsHidden=T|Text=-|Name=Series
|RECORD=41|OwnerIndex=850|IndexInSheet=20|OwnerPartId=-1|Location.X=1129|Location.Y=822|Color=8388608|FontID=1|IsHidden=T|Text=No SVHC|Name=REACH SVHC
|RECORD=41|OwnerIndex=850|IndexInSheet=21|OwnerPartId=-1|Location.X=1129|Location.Y=822|Color=8388608|FontID=1|IsHidden=T|Text=1mm|Name=Length
|RECORD=41|OwnerIndex=850|IndexInSheet=22|OwnerPartId=-1|Location.X=1129|Location.Y=822|Color=8388608|FontID=1|IsHidden=T|Text=X7R|Name=Dielectric
|RECORD=41|OwnerIndex=850|IndexInSheet=23|OwnerPartId=-1|Location.X=1129|Location.Y=822|Color=8388608|FontID=1|IsHidden=T|Text=Yes|Name=RoHS Compliant
|RECORD=41|OwnerIndex=850|IndexInSheet=24|OwnerPartId=-1|Location.X=1129|Location.Y=822|Color=8388608|FontID=1|IsHidden=T|Text=Surface Mount|Name=Mount
|RECORD=41|OwnerIndex=850|IndexInSheet=25|OwnerPartId=-1|Location.X=1129|Location.Y=822|Color=8388608|FontID=1|IsHidden=T|Text=Tape and Reel|Name=Packaging
|RECORD=41|OwnerIndex=850|IndexInSheet=26|OwnerPartId=-1|Location.X=1129|Location.Y=822|Color=8388608|FontID=1|IsHidden=T|Text=0402|Name=Case/Package
|RECORD=41|OwnerIndex=850|IndexInSheet=27|OwnerPartId=-1|Location.X=1129|Location.Y=822|Color=8388608|FontID=1|IsHidden=T|Text=0402|Name=Case Code (Imperial)
|RECORD=41|OwnerIndex=850|IndexInSheet=28|OwnerPartId=-1|Location.X=1129|Location.Y=822|Color=8388608|FontID=1|IsHidden=T|Text=SMD/SMT|Name=Termination
|RECORD=41|OwnerIndex=850|IndexInSheet=29|OwnerPartId=-1|Location.X=1129|Location.Y=822|Color=8388608|FontID=1|IsHidden=T|Text=0.02inch|Name=Width
|RECORD=41|OwnerIndex=850|IndexInSheet=30|OwnerPartId=-1|Location.X=1129|Location.Y=822|Color=8388608|FontID=1|IsHidden=T|Text=1005|Name=Case Code (Metric)
|RECORD=41|OwnerIndex=850|IndexInSheet=31|OwnerPartId=-1|Location.X=1129|Location.Y=822|Color=8388608|FontID=1|IsHidden=T|Text=10%|Name=Tolerance
|RECORD=34|OwnerIndex=850|IndexInSheet=-1|OwnerPartId=-1|Location.X=1130|Location.Y=800|Orientation=1|Color=8388608|FontID=2|Text=C94|Name=Designator|ReadOnlyState=1
|RECORD=41|OwnerIndex=850|IndexInSheet=-1|OwnerPartId=1|Location.X=1160|Location.Y=785|Orientation=1|Color=8388608|FontID=2|Text=0.1uF_25V_0402|Name=Comment
|RECORD=44|OwnerIndex=850
|RECORD=45|OwnerIndex=887|IndexInSheet=-1|UseComponentLibrary=T|ModelName=FP-0402-L_1_0_1-W_0_5_0_1-IPC_C|ModelType=PCBLIB|DatafileCount=1|ModelDatafileEntity0=FP-0402-L_1_0_1-W_0_5_0_1-IPC_C|ModelDatafileKind0=PCBLib|IsCurrent=T|DatalinksLocked=T|DatabaseDatalinksLocked=T
|RECORD=46|OwnerIndex=888
|RECORD=48|OwnerIndex=888
|RECORD=45|OwnerIndex=887|IndexInSheet=-1|UseComponentLibrary=T|ModelName=FP-0402-L_1_0_1-W_0_5_0_1-IPC_B|ModelType=PCBLIB|DatafileCount=1|ModelDatafileEntity0=FP-0402-L_1_0_1-W_0_5_0_1-IPC_B|ModelDatafileKind0=PCBLib|DatalinksLocked=T|DatabaseDatalinksLocked=T
|RECORD=46|OwnerIndex=891
|RECORD=48|OwnerIndex=891
|RECORD=45|OwnerIndex=887|IndexInSheet=-1|UseComponentLibrary=T|ModelName=FP-0402-L_1_0_1-W_0_5_0_1-MFG|ModelType=PCBLIB|DatafileCount=1|ModelDatafileEntity0=FP-0402-L_1_0_1-W_0_5_0_1-MFG|ModelDatafileKind0=PCBLib|DatalinksLocked=T|DatabaseDatalinksLocked=T
|RECORD=46|OwnerIndex=894
|RECORD=48|OwnerIndex=894
|RECORD=45|OwnerIndex=887|IndexInSheet=-1|UseComponentLibrary=T|ModelName=FP-0402-L_1_0_1-W_0_5_0_1-IPC_A|ModelType=PCBLIB|DatafileCount=1|ModelDatafileEntity0=FP-0402-L_1_0_1-W_0_5_0_1-IPC_A|ModelDatafileKind0=PCBLib|DatalinksLocked=T|DatabaseDatalinksLocked=T
|RECORD=46|OwnerIndex=897
|RECORD=48|OwnerIndex=897
|RECORD=17|IndexInSheet=74|OwnerPartId=-1|ShowNetName=T|Location.X=1140|Location.Y=870|Orientation=1|Color=128|FontID=1|Text=+3.3V
|RECORD=17|IndexInSheet=75|OwnerPartId=-1|Style=4|ShowNetName=T|Location.X=1140|Location.Y=790|Orientation=3|Color=128|FontID=1|Text=GND
|RECORD=4|IndexInSheet=76|OwnerPartId=-1|Location.X=1210|Location.Y=850|Color=8388608|FontID=1|Text=Connect FTDI to FPGA otherwise
|RECORD=17|IndexInSheet=77|OwnerPartId=-1|ShowNetName=T|Location.X=1090|Location.Y=690|Orientation=2|Color=255|FontID=1|Text=DIP_SW_UART_SEL|IsCrossSheetConnector=T
|RECORD=17|IndexInSheet=78|OwnerPartId=-1|Style=4|ShowNetName=T|Location.X=1350|Location.Y=630|Orientation=3|Color=128|FontID=1|Text=GND
|RECORD=1|LibReference=RES|PartCount=2|DisplayModeCount=2|IndexInSheet=79|OwnerPartId=-1|Location.X=1070|Location.Y=780|CurrentPartId=1|SourceLibraryName=Altium Content Vault|TargetFileName=*|AreaColor=11599871|Color=128|PartIDLocked=F|DesignItemId=CMP-2002-08434-1|AllPinCount=2
|RECORD=2|OwnerIndex=905|OwnerPartId=1|OwnerPartDisplayMode=1|FormalType=1|Electrical=4|PinConglomerate=32|PinLength=10|Location.X=1090|Location.Y=770|Name=2|Designator=2|PinPropagationDelay=0.000000E+000
|RECORD=2|OwnerIndex=905|OwnerPartId=1|OwnerPartDisplayMode=1|FormalType=1|Electrical=4|PinConglomerate=34|PinLength=10|Location.X=1070|Location.Y=770|Name=1|Designator=1|PinPropagationDelay=0.000000E+000
|RECORD=14|OwnerIndex=905|IsNotAccesible=T|IndexInSheet=2|OwnerPartId=1|OwnerPartDisplayMode=1|Location.X=1070|Location.Y=766|Corner.X=1090|Corner.Y=774|LineWidth=1|Color=16711680|AreaColor=11599871
|RECORD=2|OwnerIndex=905|OwnerPartId=1|FormalType=1|Electrical=4|PinConglomerate=32|PinLength=10|Location.X=1090|Location.Y=770|Name=2|Designator=2|PinPropagationDelay=0.000000E+000
|RECORD=2|OwnerIndex=905|OwnerPartId=1|FormalType=1|Electrical=4|PinConglomerate=34|PinLength=10|Location.X=1070|Location.Y=770|Name=1|Designator=1|PinPropagationDelay=0.000000E+000
|RECORD=6|OwnerIndex=905|IsNotAccesible=T|IndexInSheet=5|OwnerPartId=1|LineWidth=1|Color=16711680|LocationCount=10|X1=1090|Y1=770|X2=1086|Y2=770|X3=1085|Y3=768|X4=1083|Y4=772|X5=1081|Y5=768|X6=1079|Y6=772|X7=1077|Y7=768|X8=1075|Y8=772|X9=1074|Y9=770|X10=1070|Y10=770
|RECORD=41|OwnerIndex=905|IndexInSheet=6|OwnerPartId=-1|Location.X=1058|Location.Y=783|Color=8388608|FontID=1|IsHidden=T|Text=CRCW040227R0FKED|Name=Part Number
|RECORD=41|OwnerIndex=905|IndexInSheet=7|OwnerPartId=-1|Location.X=1058|Location.Y=783|Color=8388608|FontID=1|IsHidden=T|Text=Vishay Dale|Name=Manufacturer
|RECORD=34|OwnerIndex=905|IndexInSheet=-1|OwnerPartId=-1|Location.X=1050|Location.Y=770|Color=8388608|FontID=1|Text=R84|Name=Designator|ReadOnlyState=1
|RECORD=41|OwnerIndex=905|IndexInSheet=-1|OwnerPartId=-1|Location.X=1070|Location.Y=770|Color=8388608|FontID=1|Text=27_1%_0402|Name=Comment
|RECORD=44|OwnerIndex=905
|RECORD=45|OwnerIndex=920|IndexInSheet=-1|Description=Chip Resistor, 2-Leads, Body 1.00x0.50mm, IPC Medium Density|UseComponentLibrary=T|ModelName=RESC1005X40X25NL05T05|ModelType=PCBLIB|DatafileCount=1|ModelDatafileEntity0=RESC1005X40X25NL05T05|ModelDatafileKind0=PCBLib|IsCurrent=T|DatalinksLocked=T|DatabaseDatalinksLocked=T
|RECORD=46|OwnerIndex=921
|RECORD=48|OwnerIndex=921
|RECORD=41|OwnerIndex=923|IndexInSheet=-1|OwnerPartId=-1|Color=8388608|FontID=1|IsHidden=T|Text=2D|Name=Available Preview Images
|RECORD=45|OwnerIndex=920|IndexInSheet=-1|Description=Chip Resistor, 2-Leads, Body 1.00x0.50mm, IPC High Density|UseComponentLibrary=T|ModelName=RESC1005X40X25LL05T05|ModelType=PCBLIB|DatafileCount=1|ModelDatafileEntity0=RESC1005X40X25LL05T05|ModelDatafileKind0=PCBLib|DatalinksLocked=T|DatabaseDatalinksLocked=T
|RECORD=46|OwnerIndex=925
|RECORD=48|OwnerIndex=925
|RECORD=41|OwnerIndex=927|IndexInSheet=-1|OwnerPartId=-1|Color=8388608|FontID=1|IsHidden=T|Text=2D|Name=Available Preview Images
|RECORD=45|OwnerIndex=920|IndexInSheet=-1|Description=Chip Resistor, 2-Leads, Body 1.00x0.50mm, IPC Low Density|UseComponentLibrary=T|ModelName=RESC1005X40X25ML05T05|ModelType=PCBLIB|DatafileCount=1|ModelDatafileEntity0=RESC1005X40X25ML05T05|ModelDatafileKind0=PCBLib|DatalinksLocked=T|DatabaseDatalinksLocked=T
|RECORD=46|OwnerIndex=929
|RECORD=48|OwnerIndex=929
|RECORD=41|OwnerIndex=931|IndexInSheet=-1|OwnerPartId=-1|Color=8388608|FontID=1|IsHidden=T|Text=2D|Name=Available Preview Images
|RECORD=1|LibReference=RES|PartCount=2|DisplayModeCount=2|IndexInSheet=80|OwnerPartId=-1|Location.X=1070|Location.Y=740|CurrentPartId=1|SourceLibraryName=Altium Content Vault|TargetFileName=*|AreaColor=11599871|Color=128|PartIDLocked=F|DesignItemId=CMP-2002-08434-1|AllPinCount=2
|RECORD=2|OwnerIndex=933|OwnerPartId=1|OwnerPartDisplayMode=1|FormalType=1|Electrical=4|PinConglomerate=32|PinLength=10|Location.X=1090|Location.Y=730|Name=2|Designator=2|PinPropagationDelay=0.000000E+000
|RECORD=2|OwnerIndex=933|OwnerPartId=1|OwnerPartDisplayMode=1|FormalType=1|Electrical=4|PinConglomerate=34|PinLength=10|Location.X=1070|Location.Y=730|Name=1|Designator=1|PinPropagationDelay=0.000000E+000
|RECORD=14|OwnerIndex=933|IsNotAccesible=T|IndexInSheet=2|OwnerPartId=1|OwnerPartDisplayMode=1|Location.X=1070|Location.Y=726|Corner.X=1090|Corner.Y=734|LineWidth=1|Color=16711680|AreaColor=11599871
|RECORD=2|OwnerIndex=933|OwnerPartId=1|FormalType=1|Electrical=4|PinConglomerate=32|PinLength=10|Location.X=1090|Location.Y=730|Name=2|Designator=2|PinPropagationDelay=0.000000E+000
|RECORD=2|OwnerIndex=933|OwnerPartId=1|FormalType=1|Electrical=4|PinConglomerate=34|PinLength=10|Location.X=1070|Location.Y=730|Name=1|Designator=1|PinPropagationDelay=0.000000E+000
|RECORD=6|OwnerIndex=933|IsNotAccesible=T|IndexInSheet=5|OwnerPartId=1|LineWidth=1|Color=16711680|LocationCount=10|X1=1090|Y1=730|X2=1086|Y2=730|X3=1085|Y3=728|X4=1083|Y4=732|X5=1081|Y5=728|X6=1079|Y6=732|X7=1077|Y7=728|X8=1075|Y8=732|X9=1074|Y9=730|X10=1070|Y10=730
|RECORD=41|OwnerIndex=933|IndexInSheet=6|OwnerPartId=-1|Location.X=1058|Location.Y=743|Color=8388608|FontID=1|IsHidden=T|Text=CRCW040227R0FKED|Name=Part Number
|RECORD=41|OwnerIndex=933|IndexInSheet=7|OwnerPartId=-1|Location.X=1058|Location.Y=743|Color=8388608|FontID=1|IsHidden=T|Text=Vishay Dale|Name=Manufacturer
|RECORD=34|OwnerIndex=933|IndexInSheet=-1|OwnerPartId=-1|Location.X=1050|Location.Y=730|Color=8388608|FontID=1|Text=R86|Name=Designator|ReadOnlyState=1
|RECORD=41|OwnerIndex=933|IndexInSheet=-1|OwnerPartId=-1|Location.X=1070|Location.Y=730|Color=8388608|FontID=1|Text=27_1%_0402|Name=Comment
|RECORD=44|OwnerIndex=933
|RECORD=45|OwnerIndex=948|IndexInSheet=-1|Description=Chip Resistor, 2-Leads, Body 1.00x0.50mm, IPC Medium Density|UseComponentLibrary=T|ModelName=RESC1005X40X25NL05T05|ModelType=PCBLIB|DatafileCount=1|ModelDatafileEntity0=RESC1005X40X25NL05T05|ModelDatafileKind0=PCBLib|IsCurrent=T|DatalinksLocked=T|DatabaseDatalinksLocked=T
|RECORD=46|OwnerIndex=949
|RECORD=48|OwnerIndex=949
|RECORD=41|OwnerIndex=951|IndexInSheet=-1|OwnerPartId=-1|Color=8388608|FontID=1|IsHidden=T|Text=2D|Name=Available Preview Images
|RECORD=45|OwnerIndex=948|IndexInSheet=-1|Description=Chip Resistor, 2-Leads, Body 1.00x0.50mm, IPC High Density|UseComponentLibrary=T|ModelName=RESC1005X40X25LL05T05|ModelType=PCBLIB|DatafileCount=1|ModelDatafileEntity0=RESC1005X40X25LL05T05|ModelDatafileKind0=PCBLib|DatalinksLocked=T|DatabaseDatalinksLocked=T
|RECORD=46|OwnerIndex=953
|RECORD=48|OwnerIndex=953
|RECORD=41|OwnerIndex=955|IndexInSheet=-1|OwnerPartId=-1|Color=8388608|FontID=1|IsHidden=T|Text=2D|Name=Available Preview Images
|RECORD=45|OwnerIndex=948|IndexInSheet=-1|Description=Chip Resistor, 2-Leads, Body 1.00x0.50mm, IPC Low Density|UseComponentLibrary=T|ModelName=RESC1005X40X25ML05T05|ModelType=PCBLIB|DatafileCount=1|ModelDatafileEntity0=RESC1005X40X25ML05T05|ModelDatafileKind0=PCBLib|DatalinksLocked=T|DatabaseDatalinksLocked=T
|RECORD=46|OwnerIndex=957
|RECORD=48|OwnerIndex=957
|RECORD=41|OwnerIndex=959|IndexInSheet=-1|OwnerPartId=-1|Color=8388608|FontID=1|IsHidden=T|Text=2D|Name=Available Preview Images
|RECORD=1|LibReference=RES|PartCount=2|DisplayModeCount=2|IndexInSheet=81|OwnerPartId=-1|Location.X=1070|Location.Y=720|CurrentPartId=1|SourceLibraryName=Altium Content Vault|TargetFileName=*|AreaColor=11599871|Color=128|PartIDLocked=F|DesignItemId=CMP-2002-08434-1|AllPinCount=2
|RECORD=2|OwnerIndex=961|OwnerPartId=1|OwnerPartDisplayMode=1|FormalType=1|Electrical=4|PinConglomerate=32|PinLength=10|Location.X=1090|Location.Y=710|Name=2|Designator=2|PinPropagationDelay=0.000000E+000
|RECORD=2|OwnerIndex=961|OwnerPartId=1|OwnerPartDisplayMode=1|FormalType=1|Electrical=4|PinConglomerate=34|PinLength=10|Location.X=1070|Location.Y=710|Name=1|Designator=1|PinPropagationDelay=0.000000E+000
|RECORD=14|OwnerIndex=961|IsNotAccesible=T|IndexInSheet=2|OwnerPartId=1|OwnerPartDisplayMode=1|Location.X=1070|Location.Y=706|Corner.X=1090|Corner.Y=714|LineWidth=1|Color=16711680|AreaColor=11599871
|RECORD=2|OwnerIndex=961|OwnerPartId=1|FormalType=1|Electrical=4|PinConglomerate=32|PinLength=10|Location.X=1090|Location.Y=710|Name=2|Designator=2|PinPropagationDelay=0.000000E+000
|RECORD=2|OwnerIndex=961|OwnerPartId=1|FormalType=1|Electrical=4|PinConglomerate=34|PinLength=10|Location.X=1070|Location.Y=710|Name=1|Designator=1|PinPropagationDelay=0.000000E+000
|RECORD=6|OwnerIndex=961|IsNotAccesible=T|IndexInSheet=5|OwnerPartId=1|LineWidth=1|Color=16711680|LocationCount=10|X1=1090|Y1=710|X2=1086|Y2=710|X3=1085|Y3=708|X4=1083|Y4=712|X5=1081|Y5=708|X6=1079|Y6=712|X7=1077|Y7=708|X8=1075|Y8=712|X9=1074|Y9=710|X10=1070|Y10=710
|RECORD=41|OwnerIndex=961|IndexInSheet=6|OwnerPartId=-1|Location.X=1058|Location.Y=723|Color=8388608|FontID=1|IsHidden=T|Text=CRCW040227R0FKED|Name=Part Number
|RECORD=41|OwnerIndex=961|IndexInSheet=7|OwnerPartId=-1|Location.X=1058|Location.Y=723|Color=8388608|FontID=1|IsHidden=T|Text=Vishay Dale|Name=Manufacturer
|RECORD=34|OwnerIndex=961|IndexInSheet=-1|OwnerPartId=-1|Location.X=1050|Location.Y=710|Color=8388608|FontID=1|Text=R87|Name=Designator|ReadOnlyState=1
|RECORD=41|OwnerIndex=961|IndexInSheet=-1|OwnerPartId=-1|Location.X=1070|Location.Y=710|Color=8388608|FontID=1|Text=27_1%_0402|Name=Comment
|RECORD=44|OwnerIndex=961
|RECORD=45|OwnerIndex=976|IndexInSheet=-1|Description=Chip Resistor, 2-Leads, Body 1.00x0.50mm, IPC Medium Density|UseComponentLibrary=T|ModelName=RESC1005X40X25NL05T05|ModelType=PCBLIB|DatafileCount=1|ModelDatafileEntity0=RESC1005X40X25NL05T05|ModelDatafileKind0=PCBLib|IsCurrent=T|DatalinksLocked=T|DatabaseDatalinksLocked=T
|RECORD=46|OwnerIndex=977
|RECORD=48|OwnerIndex=977
|RECORD=41|OwnerIndex=979|IndexInSheet=-1|OwnerPartId=-1|Color=8388608|FontID=1|IsHidden=T|Text=2D|Name=Available Preview Images
|RECORD=45|OwnerIndex=976|IndexInSheet=-1|Description=Chip Resistor, 2-Leads, Body 1.00x0.50mm, IPC High Density|UseComponentLibrary=T|ModelName=RESC1005X40X25LL05T05|ModelType=PCBLIB|DatafileCount=1|ModelDatafileEntity0=RESC1005X40X25LL05T05|ModelDatafileKind0=PCBLib|DatalinksLocked=T|DatabaseDatalinksLocked=T
|RECORD=46|OwnerIndex=981
|RECORD=48|OwnerIndex=981
|RECORD=41|OwnerIndex=983|IndexInSheet=-1|OwnerPartId=-1|Color=8388608|FontID=1|IsHidden=T|Text=2D|Name=Available Preview Images
|RECORD=45|OwnerIndex=976|IndexInSheet=-1|Description=Chip Resistor, 2-Leads, Body 1.00x0.50mm, IPC Low Density|UseComponentLibrary=T|ModelName=RESC1005X40X25ML05T05|ModelType=PCBLIB|DatafileCount=1|ModelDatafileEntity0=RESC1005X40X25ML05T05|ModelDatafileKind0=PCBLib|DatalinksLocked=T|DatabaseDatalinksLocked=T
|RECORD=46|OwnerIndex=985
|RECORD=48|OwnerIndex=985
|RECORD=41|OwnerIndex=987|IndexInSheet=-1|OwnerPartId=-1|Color=8388608|FontID=1|IsHidden=T|Text=2D|Name=Available Preview Images
|RECORD=1|LibReference=RES|PartCount=2|DisplayModeCount=2|IndexInSheet=82|OwnerPartId=-1|Location.X=1070|Location.Y=760|CurrentPartId=1|SourceLibraryName=Altium Content Vault|TargetFileName=*|AreaColor=11599871|Color=128|PartIDLocked=F|DesignItemId=CMP-2002-08434-1|AllPinCount=2
|RECORD=2|OwnerIndex=989|OwnerPartId=1|OwnerPartDisplayMode=1|FormalType=1|Electrical=4|PinConglomerate=32|PinLength=10|Location.X=1090|Location.Y=750|Name=2|Designator=2|PinPropagationDelay=0.000000E+000
|RECORD=2|OwnerIndex=989|OwnerPartId=1|OwnerPartDisplayMode=1|FormalType=1|Electrical=4|PinConglomerate=34|PinLength=10|Location.X=1070|Location.Y=750|Name=1|Designator=1|PinPropagationDelay=0.000000E+000
|RECORD=14|OwnerIndex=989|IsNotAccesible=T|IndexInSheet=2|OwnerPartId=1|OwnerPartDisplayMode=1|Location.X=1070|Location.Y=746|Corner.X=1090|Corner.Y=754|LineWidth=1|Color=16711680|AreaColor=11599871
|RECORD=2|OwnerIndex=989|OwnerPartId=1|FormalType=1|Electrical=4|PinConglomerate=32|PinLength=10|Location.X=1090|Location.Y=750|Name=2|Designator=2|PinPropagationDelay=0.000000E+000
|RECORD=2|OwnerIndex=989|OwnerPartId=1|FormalType=1|Electrical=4|PinConglomerate=34|PinLength=10|Location.X=1070|Location.Y=750|Name=1|Designator=1|PinPropagationDelay=0.000000E+000
|RECORD=6|OwnerIndex=989|IsNotAccesible=T|IndexInSheet=5|OwnerPartId=1|LineWidth=1|Color=16711680|LocationCount=10|X1=1090|Y1=750|X2=1086|Y2=750|X3=1085|Y3=748|X4=1083|Y4=752|X5=1081|Y5=748|X6=1079|Y6=752|X7=1077|Y7=748|X8=1075|Y8=752|X9=1074|Y9=750|X10=1070|Y10=750
|RECORD=41|OwnerIndex=989|IndexInSheet=6|OwnerPartId=-1|Location.X=1058|Location.Y=763|Color=8388608|FontID=1|IsHidden=T|Text=CRCW040227R0FKED|Name=Part Number
|RECORD=41|OwnerIndex=989|IndexInSheet=7|OwnerPartId=-1|Location.X=1058|Location.Y=763|Color=8388608|FontID=1|IsHidden=T|Text=Vishay Dale|Name=Manufacturer
|RECORD=34|OwnerIndex=989|IndexInSheet=-1|OwnerPartId=-1|Location.X=1050|Location.Y=750|Color=8388608|FontID=1|Text=R85|Name=Designator|ReadOnlyState=1
|RECORD=41|OwnerIndex=989|IndexInSheet=-1|OwnerPartId=-1|Location.X=1070|Location.Y=750|Color=8388608|FontID=1|Text=27_1%_0402|Name=Comment
|RECORD=44|OwnerIndex=989
|RECORD=45|OwnerIndex=1004|IndexInSheet=-1|Description=Chip Resistor, 2-Leads, Body 1.00x0.50mm, IPC Medium Density|UseComponentLibrary=T|ModelName=RESC1005X40X25NL05T05|ModelType=PCBLIB|DatafileCount=1|ModelDatafileEntity0=RESC1005X40X25NL05T05|ModelDatafileKind0=PCBLib|IsCurrent=T|DatalinksLocked=T|DatabaseDatalinksLocked=T
|RECORD=46|OwnerIndex=1005
|RECORD=48|OwnerIndex=1005
|RECORD=41|OwnerIndex=1007|IndexInSheet=-1|OwnerPartId=-1|Color=8388608|FontID=1|IsHidden=T|Text=2D|Name=Available Preview Images
|RECORD=45|OwnerIndex=1004|IndexInSheet=-1|Description=Chip Resistor, 2-Leads, Body 1.00x0.50mm, IPC High Density|UseComponentLibrary=T|ModelName=RESC1005X40X25LL05T05|ModelType=PCBLIB|DatafileCount=1|ModelDatafileEntity0=RESC1005X40X25LL05T05|ModelDatafileKind0=PCBLib|DatalinksLocked=T|DatabaseDatalinksLocked=T
|RECORD=46|OwnerIndex=1009
|RECORD=48|OwnerIndex=1009
|RECORD=41|OwnerIndex=1011|IndexInSheet=-1|OwnerPartId=-1|Color=8388608|FontID=1|IsHidden=T|Text=2D|Name=Available Preview Images
|RECORD=45|OwnerIndex=1004|IndexInSheet=-1|Description=Chip Resistor, 2-Leads, Body 1.00x0.50mm, IPC Low Density|UseComponentLibrary=T|ModelName=RESC1005X40X25ML05T05|ModelType=PCBLIB|DatafileCount=1|ModelDatafileEntity0=RESC1005X40X25ML05T05|ModelDatafileKind0=PCBLib|DatalinksLocked=T|DatabaseDatalinksLocked=T
|RECORD=46|OwnerIndex=1013
|RECORD=48|OwnerIndex=1013
|RECORD=41|OwnerIndex=1015|IndexInSheet=-1|OwnerPartId=-1|Color=8388608|FontID=1|IsHidden=T|Text=2D|Name=Available Preview Images
|RECORD=17|IndexInSheet=83|OwnerPartId=-1|ShowNetName=T|Location.X=1390|Location.Y=770|Color=255|FontID=1|Text=UART1_TXD|IsCrossSheetConnector=T
|RECORD=17|IndexInSheet=84|OwnerPartId=-1|Style=1|ShowNetName=T|Location.X=1390|Location.Y=730|Color=255|FontID=1|Text=UART1_RXD|IsCrossSheetConnector=T
|RECORD=17|IndexInSheet=85|OwnerPartId=-1|Style=4|ShowNetName=T|Location.X=990|Location.Y=770|Orientation=2|Color=128|FontID=1|Text=GND
|RECORD=17|IndexInSheet=86|OwnerPartId=-1|Style=4|ShowNetName=T|Location.X=990|Location.Y=730|Orientation=2|Color=128|FontID=1|Text=GND
|RECORD=17|IndexInSheet=87|OwnerPartId=-1|ShowNetName=T|Location.X=1020|Location.Y=710|Orientation=2|Color=255|FontID=1|Text=FTDI_TX|IsCrossSheetConnector=T
|RECORD=17|IndexInSheet=88|OwnerPartId=-1|Style=1|ShowNetName=T|Location.X=1020|Location.Y=750|Orientation=2|Color=255|FontID=1|Text=FTDI_RX|IsCrossSheetConnector=T
|RECORD=1|LibReference=12a319ab100cd6cfe745e35972674f5|ComponentDescription=IC SWITCH SPDT DUAL 12UQFN|PartCount=2|DisplayModeCount=1|IndexInSheet=89|OwnerPartId=-1|Location.X=450|Location.Y=300|CurrentPartId=1|LibraryPath=*|SourceLibraryName=Altium Content Vault|TargetFileName=*|AreaColor=11599871|Color=128|PartIDLocked=T|DesignItemId=CMP-04892-000114-1|AllPinCount=12
|RECORD=14|OwnerIndex=1023|IsNotAccesible=T|OwnerPartId=1|Location.X=470|Location.Y=140|Corner.X=570|Corner.Y=310|LineWidth=1|Color=128|AreaColor=11599871|IsSolid=T
|RECORD=2|OwnerIndex=1023|OwnerPartId=1|Electrical=7|PinConglomerate=58|PinLength=20|Location.X=470|Location.Y=300|Name=VCC|Designator=9|PinName_PositionConglomerate=16|Name_CustomFontID=1|PinDesignator_PositionConglomerate=16|Designator_CustomFontID=1|PinPropagationDelay=0.000000E+000
|RECORD=2|OwnerIndex=1023|OwnerPartId=1|PinConglomerate=58|PinLength=20|Location.X=470|Location.Y=200|Name=SEL1|Designator=1|PinName_PositionConglomerate=16|Name_CustomFontID=1|PinDesignator_PositionConglomerate=16|Designator_CustomFontID=1|PinPropagationDelay=0.000000E+000
|RECORD=2|OwnerIndex=1023|OwnerPartId=1|PinConglomerate=58|PinLength=20|Location.X=470|Location.Y=190|Name=SEL2|Designator=5|PinName_PositionConglomerate=16|Name_CustomFontID=1|PinDesignator_PositionConglomerate=16|Designator_CustomFontID=1|PinPropagationDelay=0.000000E+000
|RECORD=2|OwnerIndex=1023|OwnerPartId=1|Electrical=4|PinConglomerate=58|PinLength=20|Location.X=470|Location.Y=260|Name=NO1|Designator=2|PinName_PositionConglomerate=16|Name_CustomFontID=1|PinDesignator_PositionConglomerate=16|Designator_CustomFontID=1|PinPropagationDelay=0.000000E+000
|RECORD=2|OwnerIndex=1023|OwnerPartId=1|Electrical=4|PinConglomerate=58|PinLength=20|Location.X=470|Location.Y=220|Name=NO2|Designator=4|PinName_PositionConglomerate=16|Name_CustomFontID=1|PinDesignator_PositionConglomerate=16|Designator_CustomFontID=1|PinPropagationDelay=0.000000E+000
|RECORD=2|OwnerIndex=1023|OwnerPartId=1|Electrical=4|PinConglomerate=56|PinLength=20|Location.X=570|Location.Y=280|Name=COM1|Designator=11|PinName_PositionConglomerate=16|Name_CustomFontID=1|PinDesignator_PositionConglomerate=16|Designator_CustomFontID=1|PinPropagationDelay=0.000000E+000
|RECORD=2|OwnerIndex=1023|OwnerPartId=1|Electrical=4|PinConglomerate=56|PinLength=20|Location.X=570|Location.Y=240|Name=COM2|Designator=7|PinName_PositionConglomerate=16|Name_CustomFontID=1|PinDesignator_PositionConglomerate=16|Designator_CustomFontID=1|PinPropagationDelay=0.000000E+000
|RECORD=2|OwnerIndex=1023|OwnerPartId=1|Electrical=3|PinConglomerate=58|PinLength=20|Location.X=470|Location.Y=150|Name=F\L\T\|Designator=12|PinName_PositionConglomerate=16|Name_CustomFontID=1|PinDesignator_PositionConglomerate=16|Designator_CustomFontID=1|PinPropagationDelay=0.000000E+000
|RECORD=2|OwnerIndex=1023|OwnerPartId=1|PinConglomerate=58|PinLength=20|Location.X=470|Location.Y=170|Name=O\E\|Designator=6|PinName_PositionConglomerate=16|Name_CustomFontID=1|PinDesignator_PositionConglomerate=16|Designator_CustomFontID=1|PinPropagationDelay=0.000000E+000
|RECORD=2|OwnerIndex=1023|OwnerPartId=1|Electrical=4|PinConglomerate=58|PinLength=20|Location.X=470|Location.Y=280|Name=NC1|Designator=10|PinName_PositionConglomerate=16|Name_CustomFontID=1|PinDesignator_PositionConglomerate=16|Designator_CustomFontID=1|PinPropagationDelay=0.000000E+000
|RECORD=2|OwnerIndex=1023|OwnerPartId=1|Electrical=4|PinConglomerate=58|PinLength=20|Location.X=470|Location.Y=240|Name=NC2|Designator=8|PinName_PositionConglomerate=16|Name_CustomFontID=1|PinDesignator_PositionConglomerate=16|Designator_CustomFontID=1|PinPropagationDelay=0.000000E+000
|RECORD=2|OwnerIndex=1023|OwnerPartId=1|Electrical=7|PinConglomerate=56|PinLength=20|Location.X=570|Location.Y=150|Name=GND|Designator=3|PinName_PositionConglomerate=16|Name_CustomFontID=1|PinDesignator_PositionConglomerate=16|Designator_CustomFontID=1|PinPropagationDelay=0.000000E+000
|RECORD=41|OwnerIndex=1023|IndexInSheet=13|OwnerPartId=-1|Location.X=448|Location.Y=310|Color=8388608|FontID=1|IsHidden=T|Text=12|Name=Number of Pins
|RECORD=41|OwnerIndex=1023|IndexInSheet=14|OwnerPartId=-1|Location.X=448|Location.Y=310|Color=8388608|FontID=1|IsHidden=T|Text=2|Name=Number of Circuits
|RECORD=41|OwnerIndex=1023|IndexInSheet=15|OwnerPartId=-1|Location.X=448|Location.Y=310|Color=8388608|FontID=1|IsHidden=T|Text=-40°C|Name=Min Operating Temperature
|RECORD=41|OwnerIndex=1023|IndexInSheet=16|OwnerPartId=-1|Location.X=448|Location.Y=310|Color=8388608|FontID=1|IsHidden=T|Text=Yes|Name=RoHS Compliant
|RECORD=41|OwnerIndex=1023|IndexInSheet=17|OwnerPartId=-1|Location.X=448|Location.Y=310|Color=8388608|FontID=1|IsHidden=T|Text=1.2GHz|Name=-3db Bandwidth
|RECORD=41|OwnerIndex=1023|IndexInSheet=18|OwnerPartId=-1|Location.X=448|Location.Y=310|Color=8388608|FontID=1|IsHidden=T|Text=125°C|Name=Max Operating Temperature
|RECORD=41|OwnerIndex=1023|IndexInSheet=19|OwnerPartId=-1|Location.X=448|Location.Y=310|Color=8388608|FontID=1|IsHidden=T|Text=2|Name=Number of Channels
|RECORD=41|OwnerIndex=1023|IndexInSheet=20|OwnerPartId=-1|Location.X=448|Location.Y=310|Color=8388608|FontID=1|IsHidden=T|Text=18R|Name=On-State Resistance
|RECORD=41|OwnerIndex=1023|IndexInSheet=21|OwnerPartId=-1|Location.X=448|Location.Y=310|Color=8388608|FontID=1|IsHidden=T|Text=Tape and Reel|Name=Packaging
|RECORD=34|OwnerIndex=1023|IndexInSheet=-1|OwnerPartId=-1|Location.X=470|Location.Y=310|Color=8388608|FontID=1|Text=U23|Name=Designator|ReadOnlyState=1
|RECORD=41|OwnerIndex=1023|IndexInSheet=-1|OwnerPartId=1|Location.X=470|Location.Y=130|Color=8388608|FontID=1|Text=TMUX1072RUTR|Name=Comment
|RECORD=44|OwnerIndex=1023
|RECORD=45|OwnerIndex=1060|IndexInSheet=-1|UseComponentLibrary=T|ModelName=FP-RUT0012A-MFG|ModelType=PCBLIB|DatafileCount=1|ModelDatafileEntity0=FP-RUT0012A-MFG|ModelDatafileKind0=PCBLib|IsCurrent=T|DatalinksLocked=T|DatabaseDatalinksLocked=T
|RECORD=46|OwnerIndex=1061
|RECORD=48|OwnerIndex=1061
|RECORD=17|IndexInSheet=90|OwnerPartId=-1|Style=4|ShowNetName=T|Location.X=430|Location.Y=140|Orientation=3|Color=128|FontID=1|Text=GND
|RECORD=1|LibReference=b4654b650e69147ec39a6b967a45e02|ComponentDescription=General Purpose Ceramic Capacitor, 0402, 100nF, 10%, X7R, 15%, 25V|PartCount=2|DisplayModeCount=1|IndexInSheet=91|OwnerPartId=-1|Location.X=390|Location.Y=330|CurrentPartId=1|LibraryPath=*|SourceLibraryName=Altium Content Vault|TargetFileName=*|AreaColor=11599871|Color=128|PartIDLocked=T|DesignItemId=CMP-2008-02519-2|AllPinCount=2
|RECORD=2|OwnerIndex=1065|OwnerPartId=1|Electrical=4|PinConglomerate=49|PinLength=7|Location.X=390|Location.Y=323|Name=1|Designator=1|PinPropagationDelay=0.000000E+000
|RECORD=2|OwnerIndex=1065|OwnerPartId=1|Electrical=4|PinConglomerate=51|PinLength=6|Location.X=390|Location.Y=316|Name=2|Designator=2|PinPropagationDelay=0.000000E+000
|RECORD=13|OwnerIndex=1065|IsNotAccesible=T|IndexInSheet=2|OwnerPartId=1|Location.X=400|Location.Y=323|Corner.X=380|Corner.Y=323|LineWidth=1|Color=16711680
|RECORD=13|OwnerIndex=1065|IsNotAccesible=T|IndexInSheet=3|OwnerPartId=1|Location.X=400|Location.Y=317|Corner.X=380|Corner.Y=317|LineWidth=1|Color=16711680
|RECORD=13|OwnerIndex=1065|IsNotAccesible=T|IndexInSheet=4|OwnerPartId=1|Location.X=390|Location.Y=323|Corner.X=390|Corner.Y=326|LineWidth=1|Color=16711680
|RECORD=13|OwnerIndex=1065|IsNotAccesible=T|IndexInSheet=5|OwnerPartId=1|Location.X=390|Location.Y=316|Corner.X=390|Corner.Y=315|LineWidth=1|Color=16711680
|RECORD=41|OwnerIndex=1065|IndexInSheet=6|OwnerPartId=-1|Location.X=379|Location.Y=332|Color=8388608|FontID=1|IsHidden=T|Text=1|Name=Package Quantity
|RECORD=41|OwnerIndex=1065|IndexInSheet=7|OwnerPartId=-1|Location.X=379|Location.Y=332|Color=8388608|FontID=1|IsHidden=T|Text=100nF|Name=Capacitance
|RECORD=41|OwnerIndex=1065|IndexInSheet=8|OwnerPartId=-1|Location.X=379|Location.Y=332|Color=8388608|FontID=1|IsHidden=T|Text=-55°C|Name=Min Operating Temperature
|RECORD=41|OwnerIndex=1065|IndexInSheet=9|OwnerPartId=-1|Location.X=379|Location.Y=332|Color=8388608|FontID=1|IsHidden=T|Text=25V|Name=Voltage
|RECORD=41|OwnerIndex=1065|IndexInSheet=10|OwnerPartId=-1|Location.X=379|Location.Y=332|Color=8388608|FontID=1|IsHidden=T|Text=25V|Name=Voltage Rating
|RECORD=41|OwnerIndex=1065|IndexInSheet=11|OwnerPartId=-1|Location.X=379|Location.Y=332|Color=8388608|FontID=1|IsHidden=T|Text=Flat|Name=Construction
|RECORD=41|OwnerIndex=1065|IndexInSheet=12|OwnerPartId=-1|Location.X=379|Location.Y=332|Color=8388608|FontID=1|IsHidden=T|Text=125°C|Name=Max Operating Temperature
|RECORD=41|OwnerIndex=1065|IndexInSheet=13|OwnerPartId=-1|Location.X=379|Location.Y=332|Color=8388608|FontID=1|IsHidden=T|Text=No|Name=Radiation Hardening
|RECORD=41|OwnerIndex=1065|IndexInSheet=14|OwnerPartId=-1|Location.X=379|Location.Y=332|Color=8388608|FontID=1|IsHidden=T|Text=0.5mm|Name=Depth
|RECORD=41|OwnerIndex=1065|IndexInSheet=15|OwnerPartId=-1|Location.X=379|Location.Y=332|Color=8388608|FontID=1|IsHidden=T|Text=0.022inch|Name=Thickness
|RECORD=41|OwnerIndex=1065|IndexInSheet=16|OwnerPartId=-1|Location.X=379|Location.Y=332|Color=8388608|FontID=1|IsHidden=T|Text=25V|Name=Voltage Rating (DC)
|RECORD=41|OwnerIndex=1065|IndexInSheet=17|OwnerPartId=-1|Location.X=379|Location.Y=332|Color=8388608|FontID=1|IsHidden=T|Text=2|Name=Number of Pins
|RECORD=41|OwnerIndex=1065|IndexInSheet=18|OwnerPartId=-1|Location.X=379|Location.Y=332|Color=8388608|FontID=1|IsHidden=T|Text=Lead Free|Name=Lead Free
|RECORD=41|OwnerIndex=1065|IndexInSheet=19|OwnerPartId=-1|Location.X=379|Location.Y=332|Color=8388608|FontID=1|IsHidden=T|Text=-|Name=Series
|RECORD=41|OwnerIndex=1065|IndexInSheet=20|OwnerPartId=-1|Location.X=379|Location.Y=332|Color=8388608|FontID=1|IsHidden=T|Text=No SVHC|Name=REACH SVHC
|RECORD=41|OwnerIndex=1065|IndexInSheet=21|OwnerPartId=-1|Location.X=379|Location.Y=332|Color=8388608|FontID=1|IsHidden=T|Text=1mm|Name=Length
|RECORD=41|OwnerIndex=1065|IndexInSheet=22|OwnerPartId=-1|Location.X=379|Location.Y=332|Color=8388608|FontID=1|IsHidden=T|Text=X7R|Name=Dielectric
|RECORD=41|OwnerIndex=1065|IndexInSheet=23|OwnerPartId=-1|Location.X=379|Location.Y=332|Color=8388608|FontID=1|IsHidden=T|Text=Yes|Name=RoHS Compliant
|RECORD=41|OwnerIndex=1065|IndexInSheet=24|OwnerPartId=-1|Location.X=379|Location.Y=332|Color=8388608|FontID=1|IsHidden=T|Text=Surface Mount|Name=Mount
|RECORD=41|OwnerIndex=1065|IndexInSheet=25|OwnerPartId=-1|Location.X=379|Location.Y=332|Color=8388608|FontID=1|IsHidden=T|Text=Tape and Reel|Name=Packaging
|RECORD=41|OwnerIndex=1065|IndexInSheet=26|OwnerPartId=-1|Location.X=379|Location.Y=332|Color=8388608|FontID=1|IsHidden=T|Text=0402|Name=Case/Package
|RECORD=41|OwnerIndex=1065|IndexInSheet=27|OwnerPartId=-1|Location.X=379|Location.Y=332|Color=8388608|FontID=1|IsHidden=T|Text=0402|Name=Case Code (Imperial)
|RECORD=41|OwnerIndex=1065|IndexInSheet=28|OwnerPartId=-1|Location.X=379|Location.Y=332|Color=8388608|FontID=1|IsHidden=T|Text=SMD/SMT|Name=Termination
|RECORD=41|OwnerIndex=1065|IndexInSheet=29|OwnerPartId=-1|Location.X=379|Location.Y=332|Color=8388608|FontID=1|IsHidden=T|Text=0.02inch|Name=Width
|RECORD=41|OwnerIndex=1065|IndexInSheet=30|OwnerPartId=-1|Location.X=379|Location.Y=332|Color=8388608|FontID=1|IsHidden=T|Text=1005|Name=Case Code (Metric)
|RECORD=41|OwnerIndex=1065|IndexInSheet=31|OwnerPartId=-1|Location.X=379|Location.Y=332|Color=8388608|FontID=1|IsHidden=T|Text=10%|Name=Tolerance
|RECORD=34|OwnerIndex=1065|IndexInSheet=-1|OwnerPartId=-1|Location.X=380|Location.Y=310|Orientation=1|Color=8388608|FontID=2|Text=C96|Name=Designator|ReadOnlyState=1
|RECORD=41|OwnerIndex=1065|IndexInSheet=-1|OwnerPartId=1|Location.X=410|Location.Y=295|Orientation=1|Color=8388608|FontID=2|Text=0.1uF_25V_0402|Name=Comment
|RECORD=44|OwnerIndex=1065
|RECORD=45|OwnerIndex=1102|IndexInSheet=-1|UseComponentLibrary=T|ModelName=FP-0402-L_1_0_1-W_0_5_0_1-IPC_C|ModelType=PCBLIB|DatafileCount=1|ModelDatafileEntity0=FP-0402-L_1_0_1-W_0_5_0_1-IPC_C|ModelDatafileKind0=PCBLib|IsCurrent=T|DatalinksLocked=T|DatabaseDatalinksLocked=T
|RECORD=46|OwnerIndex=1103
|RECORD=48|OwnerIndex=1103
|RECORD=45|OwnerIndex=1102|IndexInSheet=-1|UseComponentLibrary=T|ModelName=FP-0402-L_1_0_1-W_0_5_0_1-IPC_B|ModelType=PCBLIB|DatafileCount=1|ModelDatafileEntity0=FP-0402-L_1_0_1-W_0_5_0_1-IPC_B|ModelDatafileKind0=PCBLib|DatalinksLocked=T|DatabaseDatalinksLocked=T
|RECORD=46|OwnerIndex=1106
|RECORD=48|OwnerIndex=1106
|RECORD=45|OwnerIndex=1102|IndexInSheet=-1|UseComponentLibrary=T|ModelName=FP-0402-L_1_0_1-W_0_5_0_1-MFG|ModelType=PCBLIB|DatafileCount=1|ModelDatafileEntity0=FP-0402-L_1_0_1-W_0_5_0_1-MFG|ModelDatafileKind0=PCBLib|DatalinksLocked=T|DatabaseDatalinksLocked=T
|RECORD=46|OwnerIndex=1109
|RECORD=48|OwnerIndex=1109
|RECORD=45|OwnerIndex=1102|IndexInSheet=-1|UseComponentLibrary=T|ModelName=FP-0402-L_1_0_1-W_0_5_0_1-IPC_A|ModelType=PCBLIB|DatafileCount=1|ModelDatafileEntity0=FP-0402-L_1_0_1-W_0_5_0_1-IPC_A|ModelDatafileKind0=PCBLib|DatalinksLocked=T|DatabaseDatalinksLocked=T
|RECORD=46|OwnerIndex=1112
|RECORD=48|OwnerIndex=1112
|RECORD=17|IndexInSheet=92|OwnerPartId=-1|ShowNetName=T|Location.X=390|Location.Y=380|Orientation=1|Color=128|FontID=1|Text=+3.3V
|RECORD=17|IndexInSheet=93|OwnerPartId=-1|Style=4|ShowNetName=T|Location.X=390|Location.Y=300|Orientation=3|Color=128|FontID=1|Text=GND
|RECORD=4|IndexInSheet=94|OwnerPartId=-1|Location.X=710|Location.Y=370|Color=8388608|FontID=1|Text=Atomic clock PPS input / output select
|RECORD=17|IndexInSheet=95|OwnerPartId=-1|ShowNetName=T|Location.X=340|Location.Y=200|Orientation=2|Color=255|FontID=1|Text=DIP_SW_PPS_SEL|IsCrossSheetConnector=T
|RECORD=17|IndexInSheet=96|OwnerPartId=-1|Style=4|ShowNetName=T|Location.X=600|Location.Y=140|Orientation=3|Color=128|FontID=1|Text=GND
|RECORD=17|IndexInSheet=97|OwnerPartId=-1|ShowNetName=T|Location.X=260|Location.Y=280|Orientation=2|Color=255|FontID=1|Text=MAC_PPS_OUT|IsCrossSheetConnector=T
|RECORD=4|IndexInSheet=98|OwnerPartId=-1|Location.X=60|Location.Y=280|Color=8388608|FontID=1|Text=Single ended PPS output
|RECORD=1|LibReference=RES|PartCount=2|DisplayModeCount=2|IndexInSheet=99|OwnerPartId=-1|Location.X=300|Location.Y=290|CurrentPartId=1|SourceLibraryName=Altium Content Vault|TargetFileName=*|AreaColor=11599871|Color=128|PartIDLocked=F|DesignItemId=CMP-2002-07709-1|AllPinCount=2
|RECORD=2|OwnerIndex=1122|OwnerPartId=1|OwnerPartDisplayMode=1|FormalType=1|Electrical=4|PinConglomerate=32|PinLength=10|Location.X=320|Location.Y=280|Name=2|Designator=2|PinPropagationDelay=0.000000E+000
|RECORD=2|OwnerIndex=1122|OwnerPartId=1|OwnerPartDisplayMode=1|FormalType=1|Electrical=4|PinConglomerate=34|PinLength=10|Location.X=300|Location.Y=280|Name=1|Designator=1|PinPropagationDelay=0.000000E+000
|RECORD=14|OwnerIndex=1122|IsNotAccesible=T|IndexInSheet=2|OwnerPartId=1|OwnerPartDisplayMode=1|Location.X=300|Location.Y=276|Corner.X=320|Corner.Y=284|LineWidth=1|Color=16711680|AreaColor=11599871
|RECORD=2|OwnerIndex=1122|OwnerPartId=1|FormalType=1|Electrical=4|PinConglomerate=32|PinLength=10|Location.X=320|Location.Y=280|Name=2|Designator=2|PinPropagationDelay=0.000000E+000
|RECORD=2|OwnerIndex=1122|OwnerPartId=1|FormalType=1|Electrical=4|PinConglomerate=34|PinLength=10|Location.X=300|Location.Y=280|Name=1|Designator=1|PinPropagationDelay=0.000000E+000
|RECORD=6|OwnerIndex=1122|IsNotAccesible=T|IndexInSheet=5|OwnerPartId=1|LineWidth=1|Color=16711680|LocationCount=10|X1=320|Y1=280|X2=316|Y2=280|X3=315|Y3=278|X4=313|Y4=282|X5=311|Y5=278|X6=309|Y6=282|X7=307|Y7=278|X8=305|Y8=282|X9=304|Y9=280|X10=300|Y10=280
|RECORD=41|OwnerIndex=1122|IndexInSheet=6|OwnerPartId=-1|Location.X=288|Location.Y=293|Color=8388608|FontID=1|IsHidden=T|Text=Yageo / Phycomp|Name=Manufacturer
|RECORD=41|OwnerIndex=1122|IndexInSheet=7|OwnerPartId=-1|Location.X=288|Location.Y=293|Color=8388608|FontID=1|IsHidden=T|Text=RC0402FR-0749R9L|Name=Part Number
|RECORD=34|OwnerIndex=1122|IndexInSheet=-1|OwnerPartId=-1|Location.X=280|Location.Y=280|Color=8388608|FontID=1|Text=R96|Name=Designator|ReadOnlyState=1
|RECORD=41|OwnerIndex=1122|IndexInSheet=-1|OwnerPartId=-1|Location.X=320|Location.Y=280|Color=8388608|FontID=1|Text=49.9_1%_0402|Name=Comment
|RECORD=44|OwnerIndex=1122
|RECORD=45|OwnerIndex=1137|IndexInSheet=-1|Description=Chip Resistor, 2-Leads, Body 1.00x0.50mm, IPC High Density|UseComponentLibrary=T|ModelName=RESC1005X40X25LL05T10|ModelType=PCBLIB|DatafileCount=1|ModelDatafileEntity0=RESC1005X40X25LL05T10|ModelDatafileKind0=PCBLib|IsCurrent=T|DatalinksLocked=T|DatabaseDatalinksLocked=T
|RECORD=46|OwnerIndex=1138
|RECORD=48|OwnerIndex=1138
|RECORD=41|OwnerIndex=1140|IndexInSheet=-1|OwnerPartId=-1|Color=8388608|FontID=1|IsHidden=T|Text=2D|Name=Available Preview Images
|RECORD=45|OwnerIndex=1137|IndexInSheet=-1|Description=Chip Resistor, 2-Leads, Body 1.00x0.50mm, IPC Low Density|UseComponentLibrary=T|ModelName=RESC1005X40X25ML05T10|ModelType=PCBLIB|DatafileCount=1|ModelDatafileEntity0=RESC1005X40X25ML05T10|ModelDatafileKind0=PCBLib|DatalinksLocked=T|DatabaseDatalinksLocked=T
|RECORD=46|OwnerIndex=1142
|RECORD=48|OwnerIndex=1142
|RECORD=41|OwnerIndex=1144|IndexInSheet=-1|OwnerPartId=-1|Color=8388608|FontID=1|IsHidden=T|Text=2D|Name=Available Preview Images
|RECORD=45|OwnerIndex=1137|IndexInSheet=-1|Description=Chip Resistor, 2-Leads, Body 1.00x0.50mm, IPC Medium Density|UseComponentLibrary=T|ModelName=RESC1005X40X25NL05T10|ModelType=PCBLIB|DatafileCount=1|ModelDatafileEntity0=RESC1005X40X25NL05T10|ModelDatafileKind0=PCBLib|DatalinksLocked=T|DatabaseDatalinksLocked=T
|RECORD=46|OwnerIndex=1146
|RECORD=48|OwnerIndex=1146
|RECORD=41|OwnerIndex=1148|IndexInSheet=-1|OwnerPartId=-1|Color=8388608|FontID=1|IsHidden=T|Text=2D|Name=Available Preview Images
|RECORD=17|IndexInSheet=100|OwnerPartId=-1|Style=1|ShowNetName=T|Location.X=660|Location.Y=280|Color=255|FontID=1|Text=FPGA_MAC_PPS_OUT-|IsCrossSheetConnector=T
|RECORD=4|IndexInSheet=101|OwnerPartId=-1|Location.X=800|Location.Y=280|Color=8388608|FontID=1|Text=FPGA Single ended PPS Input
|RECORD=17|IndexInSheet=102|OwnerPartId=-1|ShowNetName=T|Location.X=260|Location.Y=260|Orientation=2|Color=255|FontID=1|Text=FPGA_MAC_PPSDIFF_OUT|IsCrossSheetConnector=T
|RECORD=1|LibReference=RES|PartCount=2|DisplayModeCount=2|IndexInSheet=103|OwnerPartId=-1|Location.X=300|Location.Y=270|CurrentPartId=1|SourceLibraryName=Altium Content Vault|TargetFileName=*|AreaColor=11599871|Color=128|PartIDLocked=F|DesignItemId=CMP-2002-07709-1|AllPinCount=2
|RECORD=2|OwnerIndex=1153|OwnerPartId=1|OwnerPartDisplayMode=1|FormalType=1|Electrical=4|PinConglomerate=32|PinLength=10|Location.X=320|Location.Y=260|Name=2|Designator=2|PinPropagationDelay=0.000000E+000
|RECORD=2|OwnerIndex=1153|OwnerPartId=1|OwnerPartDisplayMode=1|FormalType=1|Electrical=4|PinConglomerate=34|PinLength=10|Location.X=300|Location.Y=260|Name=1|Designator=1|PinPropagationDelay=0.000000E+000
|RECORD=14|OwnerIndex=1153|IsNotAccesible=T|IndexInSheet=2|OwnerPartId=1|OwnerPartDisplayMode=1|Location.X=300|Location.Y=256|Corner.X=320|Corner.Y=264|LineWidth=1|Color=16711680|AreaColor=11599871
|RECORD=2|OwnerIndex=1153|OwnerPartId=1|FormalType=1|Electrical=4|PinConglomerate=32|PinLength=10|Location.X=320|Location.Y=260|Name=2|Designator=2|PinPropagationDelay=0.000000E+000
|RECORD=2|OwnerIndex=1153|OwnerPartId=1|FormalType=1|Electrical=4|PinConglomerate=34|PinLength=10|Location.X=300|Location.Y=260|Name=1|Designator=1|PinPropagationDelay=0.000000E+000
|RECORD=6|OwnerIndex=1153|IsNotAccesible=T|IndexInSheet=5|OwnerPartId=1|LineWidth=1|Color=16711680|LocationCount=10|X1=320|Y1=260|X2=316|Y2=260|X3=315|Y3=258|X4=313|Y4=262|X5=311|Y5=258|X6=309|Y6=262|X7=307|Y7=258|X8=305|Y8=262|X9=304|Y9=260|X10=300|Y10=260
|RECORD=41|OwnerIndex=1153|IndexInSheet=6|OwnerPartId=-1|Location.X=288|Location.Y=273|Color=8388608|FontID=1|IsHidden=T|Text=Yageo / Phycomp|Name=Manufacturer
|RECORD=41|OwnerIndex=1153|IndexInSheet=7|OwnerPartId=-1|Location.X=288|Location.Y=273|Color=8388608|FontID=1|IsHidden=T|Text=RC0402FR-0749R9L|Name=Part Number
|RECORD=34|OwnerIndex=1153|IndexInSheet=-1|OwnerPartId=-1|Location.X=280|Location.Y=260|Color=8388608|FontID=1|Text=R97|Name=Designator|ReadOnlyState=1
|RECORD=41|OwnerIndex=1153|IndexInSheet=-1|OwnerPartId=-1|Location.X=320|Location.Y=260|Color=8388608|FontID=1|Text=49.9_1%_0402|Name=Comment
|RECORD=44|OwnerIndex=1153
|RECORD=45|OwnerIndex=1168|IndexInSheet=-1|Description=Chip Resistor, 2-Leads, Body 1.00x0.50mm, IPC High Density|UseComponentLibrary=T|ModelName=RESC1005X40X25LL05T10|ModelType=PCBLIB|DatafileCount=1|ModelDatafileEntity0=RESC1005X40X25LL05T10|ModelDatafileKind0=PCBLib|IsCurrent=T|DatalinksLocked=T|DatabaseDatalinksLocked=T
|RECORD=46|OwnerIndex=1169
|RECORD=48|OwnerIndex=1169
|RECORD=41|OwnerIndex=1171|IndexInSheet=-1|OwnerPartId=-1|Color=8388608|FontID=1|IsHidden=T|Text=2D|Name=Available Preview Images
|RECORD=45|OwnerIndex=1168|IndexInSheet=-1|Description=Chip Resistor, 2-Leads, Body 1.00x0.50mm, IPC Low Density|UseComponentLibrary=T|ModelName=RESC1005X40X25ML05T10|ModelType=PCBLIB|DatafileCount=1|ModelDatafileEntity0=RESC1005X40X25ML05T10|ModelDatafileKind0=PCBLib|DatalinksLocked=T|DatabaseDatalinksLocked=T
|RECORD=46|OwnerIndex=1173
|RECORD=48|OwnerIndex=1173
|RECORD=41|OwnerIndex=1175|IndexInSheet=-1|OwnerPartId=-1|Color=8388608|FontID=1|IsHidden=T|Text=2D|Name=Available Preview Images
|RECORD=45|OwnerIndex=1168|IndexInSheet=-1|Description=Chip Resistor, 2-Leads, Body 1.00x0.50mm, IPC Medium Density|UseComponentLibrary=T|ModelName=RESC1005X40X25NL05T10|ModelType=PCBLIB|DatafileCount=1|ModelDatafileEntity0=RESC1005X40X25NL05T10|ModelDatafileKind0=PCBLib|DatalinksLocked=T|DatabaseDatalinksLocked=T
|RECORD=46|OwnerIndex=1177
|RECORD=48|OwnerIndex=1177
|RECORD=41|OwnerIndex=1179|IndexInSheet=-1|OwnerPartId=-1|Color=8388608|FontID=1|IsHidden=T|Text=2D|Name=Available Preview Images
|RECORD=4|IndexInSheet=104|OwnerPartId=-1|Location.X=70|Location.Y=260|Color=8388608|FontID=1|Text=Diff PPS Output
|RECORD=17|IndexInSheet=105|OwnerPartId=-1|Style=1|ShowNetName=T|Location.X=260|Location.Y=240|Orientation=2|Color=255|FontID=1|Text=MAC_PPS_IN|IsCrossSheetConnector=T
|RECORD=1|LibReference=RES|PartCount=2|DisplayModeCount=2|IndexInSheet=106|OwnerPartId=-1|Location.X=300|Location.Y=250|CurrentPartId=1|SourceLibraryName=Altium Content Vault|TargetFileName=*|AreaColor=11599871|Color=128|PartIDLocked=F|DesignItemId=CMP-2002-07709-1|AllPinCount=2
|RECORD=2|OwnerIndex=1183|OwnerPartId=1|OwnerPartDisplayMode=1|FormalType=1|Electrical=4|PinConglomerate=32|PinLength=10|Location.X=320|Location.Y=240|Name=2|Designator=2|PinPropagationDelay=0.000000E+000
|RECORD=2|OwnerIndex=1183|OwnerPartId=1|OwnerPartDisplayMode=1|FormalType=1|Electrical=4|PinConglomerate=34|PinLength=10|Location.X=300|Location.Y=240|Name=1|Designator=1|PinPropagationDelay=0.000000E+000
|RECORD=14|OwnerIndex=1183|IsNotAccesible=T|IndexInSheet=2|OwnerPartId=1|OwnerPartDisplayMode=1|Location.X=300|Location.Y=236|Corner.X=320|Corner.Y=244|LineWidth=1|Color=16711680|AreaColor=11599871
|RECORD=2|OwnerIndex=1183|OwnerPartId=1|FormalType=1|Electrical=4|PinConglomerate=32|PinLength=10|Location.X=320|Location.Y=240|Name=2|Designator=2|PinPropagationDelay=0.000000E+000
|RECORD=2|OwnerIndex=1183|OwnerPartId=1|FormalType=1|Electrical=4|PinConglomerate=34|PinLength=10|Location.X=300|Location.Y=240|Name=1|Designator=1|PinPropagationDelay=0.000000E+000
|RECORD=6|OwnerIndex=1183|IsNotAccesible=T|IndexInSheet=5|OwnerPartId=1|LineWidth=1|Color=16711680|LocationCount=10|X1=320|Y1=240|X2=316|Y2=240|X3=315|Y3=238|X4=313|Y4=242|X5=311|Y5=238|X6=309|Y6=242|X7=307|Y7=238|X8=305|Y8=242|X9=304|Y9=240|X10=300|Y10=240
|RECORD=41|OwnerIndex=1183|IndexInSheet=6|OwnerPartId=-1|Location.X=288|Location.Y=253|Color=8388608|FontID=1|IsHidden=T|Text=Yageo / Phycomp|Name=Manufacturer
|RECORD=41|OwnerIndex=1183|IndexInSheet=7|OwnerPartId=-1|Location.X=288|Location.Y=253|Color=8388608|FontID=1|IsHidden=T|Text=RC0402FR-0749R9L|Name=Part Number
|RECORD=34|OwnerIndex=1183|IndexInSheet=-1|OwnerPartId=-1|Location.X=280|Location.Y=240|Color=8388608|FontID=1|Text=R98|Name=Designator|ReadOnlyState=1
|RECORD=41|OwnerIndex=1183|IndexInSheet=-1|OwnerPartId=-1|Location.X=320|Location.Y=240|Color=8388608|FontID=1|Text=49.9_1%_0402|Name=Comment
|RECORD=44|OwnerIndex=1183
|RECORD=45|OwnerIndex=1198|IndexInSheet=-1|Description=Chip Resistor, 2-Leads, Body 1.00x0.50mm, IPC High Density|UseComponentLibrary=T|ModelName=RESC1005X40X25LL05T10|ModelType=PCBLIB|DatafileCount=1|ModelDatafileEntity0=RESC1005X40X25LL05T10|ModelDatafileKind0=PCBLib|IsCurrent=T|DatalinksLocked=T|DatabaseDatalinksLocked=T
|RECORD=46|OwnerIndex=1199
|RECORD=48|OwnerIndex=1199
|RECORD=41|OwnerIndex=1201|IndexInSheet=-1|OwnerPartId=-1|Color=8388608|FontID=1|IsHidden=T|Text=2D|Name=Available Preview Images
|RECORD=45|OwnerIndex=1198|IndexInSheet=-1|Description=Chip Resistor, 2-Leads, Body 1.00x0.50mm, IPC Low Density|UseComponentLibrary=T|ModelName=RESC1005X40X25ML05T10|ModelType=PCBLIB|DatafileCount=1|ModelDatafileEntity0=RESC1005X40X25ML05T10|ModelDatafileKind0=PCBLib|DatalinksLocked=T|DatabaseDatalinksLocked=T
|RECORD=46|OwnerIndex=1203
|RECORD=48|OwnerIndex=1203
|RECORD=41|OwnerIndex=1205|IndexInSheet=-1|OwnerPartId=-1|Color=8388608|FontID=1|IsHidden=T|Text=2D|Name=Available Preview Images
|RECORD=45|OwnerIndex=1198|IndexInSheet=-1|Description=Chip Resistor, 2-Leads, Body 1.00x0.50mm, IPC Medium Density|UseComponentLibrary=T|ModelName=RESC1005X40X25NL05T10|ModelType=PCBLIB|DatafileCount=1|ModelDatafileEntity0=RESC1005X40X25NL05T10|ModelDatafileKind0=PCBLib|DatalinksLocked=T|DatabaseDatalinksLocked=T
|RECORD=46|OwnerIndex=1207
|RECORD=48|OwnerIndex=1207
|RECORD=41|OwnerIndex=1209|IndexInSheet=-1|OwnerPartId=-1|Color=8388608|FontID=1|IsHidden=T|Text=2D|Name=Available Preview Images
|RECORD=1|LibReference=RES|PartCount=2|DisplayModeCount=2|IndexInSheet=107|OwnerPartId=-1|Location.X=300|Location.Y=230|CurrentPartId=1|SourceLibraryName=Altium Content Vault|TargetFileName=*|AreaColor=11599871|Color=128|PartIDLocked=F|DesignItemId=CMP-2002-07709-1|AllPinCount=2
|RECORD=2|OwnerIndex=1211|OwnerPartId=1|OwnerPartDisplayMode=1|FormalType=1|Electrical=4|PinConglomerate=32|PinLength=10|Location.X=320|Location.Y=220|Name=2|Designator=2|PinPropagationDelay=0.000000E+000
|RECORD=2|OwnerIndex=1211|OwnerPartId=1|OwnerPartDisplayMode=1|FormalType=1|Electrical=4|PinConglomerate=34|PinLength=10|Location.X=300|Location.Y=220|Name=1|Designator=1|PinPropagationDelay=0.000000E+000
|RECORD=14|OwnerIndex=1211|IsNotAccesible=T|IndexInSheet=2|OwnerPartId=1|OwnerPartDisplayMode=1|Location.X=300|Location.Y=216|Corner.X=320|Corner.Y=224|LineWidth=1|Color=16711680|AreaColor=11599871
|RECORD=2|OwnerIndex=1211|OwnerPartId=1|FormalType=1|Electrical=4|PinConglomerate=32|PinLength=10|Location.X=320|Location.Y=220|Name=2|Designator=2|PinPropagationDelay=0.000000E+000
|RECORD=2|OwnerIndex=1211|OwnerPartId=1|FormalType=1|Electrical=4|PinConglomerate=34|PinLength=10|Location.X=300|Location.Y=220|Name=1|Designator=1|PinPropagationDelay=0.000000E+000
|RECORD=6|OwnerIndex=1211|IsNotAccesible=T|IndexInSheet=5|OwnerPartId=1|LineWidth=1|Color=16711680|LocationCount=10|X1=320|Y1=220|X2=316|Y2=220|X3=315|Y3=218|X4=313|Y4=222|X5=311|Y5=218|X6=309|Y6=222|X7=307|Y7=218|X8=305|Y8=222|X9=304|Y9=220|X10=300|Y10=220
|RECORD=41|OwnerIndex=1211|IndexInSheet=6|OwnerPartId=-1|Location.X=288|Location.Y=233|Color=8388608|FontID=1|IsHidden=T|Text=Yageo / Phycomp|Name=Manufacturer
|RECORD=41|OwnerIndex=1211|IndexInSheet=7|OwnerPartId=-1|Location.X=288|Location.Y=233|Color=8388608|FontID=1|IsHidden=T|Text=RC0402FR-0749R9L|Name=Part Number
|RECORD=34|OwnerIndex=1211|IndexInSheet=-1|OwnerPartId=-1|Location.X=280|Location.Y=220|Color=8388608|FontID=1|Text=R99|Name=Designator|ReadOnlyState=1
|RECORD=41|OwnerIndex=1211|IndexInSheet=-1|OwnerPartId=-1|Location.X=320|Location.Y=220|Color=8388608|FontID=1|Text=49.9_1%_0402|Name=Comment
|RECORD=44|OwnerIndex=1211
|RECORD=45|OwnerIndex=1226|IndexInSheet=-1|Description=Chip Resistor, 2-Leads, Body 1.00x0.50mm, IPC High Density|UseComponentLibrary=T|ModelName=RESC1005X40X25LL05T10|ModelType=PCBLIB|DatafileCount=1|ModelDatafileEntity0=RESC1005X40X25LL05T10|ModelDatafileKind0=PCBLib|IsCurrent=T|DatalinksLocked=T|DatabaseDatalinksLocked=T
|RECORD=46|OwnerIndex=1227
|RECORD=48|OwnerIndex=1227
|RECORD=41|OwnerIndex=1229|IndexInSheet=-1|OwnerPartId=-1|Color=8388608|FontID=1|IsHidden=T|Text=2D|Name=Available Preview Images
|RECORD=45|OwnerIndex=1226|IndexInSheet=-1|Description=Chip Resistor, 2-Leads, Body 1.00x0.50mm, IPC Low Density|UseComponentLibrary=T|ModelName=RESC1005X40X25ML05T10|ModelType=PCBLIB|DatafileCount=1|ModelDatafileEntity0=RESC1005X40X25ML05T10|ModelDatafileKind0=PCBLib|DatalinksLocked=T|DatabaseDatalinksLocked=T
|RECORD=46|OwnerIndex=1231
|RECORD=48|OwnerIndex=1231
|RECORD=41|OwnerIndex=1233|IndexInSheet=-1|OwnerPartId=-1|Color=8388608|FontID=1|IsHidden=T|Text=2D|Name=Available Preview Images
|RECORD=45|OwnerIndex=1226|IndexInSheet=-1|Description=Chip Resistor, 2-Leads, Body 1.00x0.50mm, IPC Medium Density|UseComponentLibrary=T|ModelName=RESC1005X40X25NL05T10|ModelType=PCBLIB|DatafileCount=1|ModelDatafileEntity0=RESC1005X40X25NL05T10|ModelDatafileKind0=PCBLib|DatalinksLocked=T|DatabaseDatalinksLocked=T
|RECORD=46|OwnerIndex=1235
|RECORD=48|OwnerIndex=1235
|RECORD=41|OwnerIndex=1237|IndexInSheet=-1|OwnerPartId=-1|Color=8388608|FontID=1|IsHidden=T|Text=2D|Name=Available Preview Images
|RECORD=4|IndexInSheet=108|OwnerPartId=-1|Location.X=60|Location.Y=240|Color=8388608|FontID=1|Text=Single ended PPS input
|RECORD=17|IndexInSheet=109|OwnerPartId=-1|Style=1|ShowNetName=T|Location.X=260|Location.Y=220|Orientation=2|Color=255|FontID=1|Text=FPGA_MAC_PPS_DIFF_IN0|IsCrossSheetConnector=T
|RECORD=4|IndexInSheet=110|OwnerPartId=-1|Location.X=40|Location.Y=200|Color=8388608|FontID=1|Text=Single ended to diff PPS input
|RECORD=17|IndexInSheet=111|OwnerPartId=-1|ShowNetName=T|Location.X=660|Location.Y=240|Color=255|FontID=1|Text=FPGA_MAC_PPS_IN0-|IsCrossSheetConnector=T
|RECORD=4|IndexInSheet=112|OwnerPartId=-1|Location.X=800|Location.Y=230|Color=8388608|FontID=1|Text=FPGA Single ended PPS Output
|RECORD=43|IndexInSheet=113|OwnerPartId=-1|Location.X=250|Location.Y=810|Color=255|Name=DIFFPAIR
|RECORD=41|OwnerIndex=1244|OwnerPartId=-1|Location.X=250|Location.Y=810|Color=8388608|FontID=1|IsHidden=T|Text=True|Name=DifferentialPair
|RECORD=43|IndexInSheet=114|OwnerPartId=-1|Location.X=250|Location.Y=830|Color=255|Name=DIFFPAIR
|RECORD=41|OwnerIndex=1246|OwnerPartId=-1|Location.X=250|Location.Y=830|Color=8388608|FontID=1|IsHidden=T|Text=True|Name=DifferentialPair
|RECORD=43|IndexInSheet=115|OwnerPartId=-1|Location.X=560|Location.Y=820|Color=255|Name=DIFFPAIR
|RECORD=41|OwnerIndex=1248|OwnerPartId=-1|Location.X=560|Location.Y=820|Color=8388608|FontID=1|IsHidden=T|Text=True|Name=DifferentialPair
|RECORD=43|IndexInSheet=116|OwnerPartId=-1|Location.X=560|Location.Y=810|Color=255|Name=DIFFPAIR
|RECORD=41|OwnerIndex=1250|OwnerPartId=-1|Location.X=560|Location.Y=810|Color=8388608|FontID=1|IsHidden=T|Text=True|Name=DifferentialPair
|RECORD=1|LibReference=RES|PartCount=2|DisplayModeCount=2|IndexInSheet=117|OwnerPartId=-1|Location.X=1310|Location.Y=390|CurrentPartId=1|SourceLibraryName=Altium Content Vault|TargetFileName=*|AreaColor=11599871|Color=128|PartIDLocked=F|DesignItemId=CMP-2002-08434-1|AllPinCount=2|ComponentKindVersion2=5
|RECORD=2|OwnerIndex=1252|OwnerPartId=1|OwnerPartDisplayMode=1|FormalType=1|Electrical=4|PinConglomerate=32|PinLength=10|Location.X=1330|Location.Y=380|Name=2|Designator=2|PinPropagationDelay=0.000000E+000
|RECORD=2|OwnerIndex=1252|OwnerPartId=1|OwnerPartDisplayMode=1|FormalType=1|Electrical=4|PinConglomerate=34|PinLength=10|Location.X=1310|Location.Y=380|Name=1|Designator=1|PinPropagationDelay=0.000000E+000
|RECORD=14|OwnerIndex=1252|IsNotAccesible=T|IndexInSheet=2|OwnerPartId=1|OwnerPartDisplayMode=1|Location.X=1310|Location.Y=376|Corner.X=1330|Corner.Y=384|LineWidth=1|Color=16711680|AreaColor=11599871
|RECORD=2|OwnerIndex=1252|OwnerPartId=1|FormalType=1|Electrical=4|PinConglomerate=32|PinLength=10|Location.X=1330|Location.Y=380|Name=2|Designator=2|PinPropagationDelay=0.000000E+000
|RECORD=2|OwnerIndex=1252|OwnerPartId=1|FormalType=1|Electrical=4|PinConglomerate=34|PinLength=10|Location.X=1310|Location.Y=380|Name=1|Designator=1|PinPropagationDelay=0.000000E+000
|RECORD=6|OwnerIndex=1252|IsNotAccesible=T|IndexInSheet=5|OwnerPartId=1|LineWidth=1|Color=16711680|LocationCount=10|X1=1330|Y1=380|X2=1326|Y2=380|X3=1325|Y3=378|X4=1323|Y4=382|X5=1321|Y5=378|X6=1319|Y6=382|X7=1317|Y7=378|X8=1315|Y8=382|X9=1314|Y9=380|X10=1310|Y10=380
|RECORD=41|OwnerIndex=1252|IndexInSheet=6|OwnerPartId=-1|Location.X=1298|Location.Y=393|Color=8388608|FontID=1|IsHidden=T|Text=CRCW040227R0FKED|Name=Part Number
|RECORD=41|OwnerIndex=1252|IndexInSheet=7|OwnerPartId=-1|Location.X=1298|Location.Y=393|Color=8388608|FontID=1|IsHidden=T|Text=Vishay Dale|Name=Manufacturer
|RECORD=34|OwnerIndex=1252|IndexInSheet=-1|OwnerPartId=-1|Location.X=1290|Location.Y=380|Color=8388608|FontID=1|Text=R102|Name=Designator|ReadOnlyState=1
|RECORD=41|OwnerIndex=1252|IndexInSheet=-1|OwnerPartId=-1|Location.X=1310|Location.Y=380|Color=8388608|FontID=1|Text=DNI_27_1%_0402|Name=Comment
|RECORD=44|OwnerIndex=1252
|RECORD=45|OwnerIndex=1267|IndexInSheet=-1|Description=Chip Resistor, 2-Leads, Body 1.00x0.50mm, IPC Medium Density|UseComponentLibrary=T|ModelName=RESC1005X40X25NL05T05|ModelType=PCBLIB|DatafileCount=1|ModelDatafileEntity0=RESC1005X40X25NL05T05|ModelDatafileKind0=PCBLib|IsCurrent=T|DatalinksLocked=T|DatabaseDatalinksLocked=T
|RECORD=46|OwnerIndex=1268
|RECORD=48|OwnerIndex=1268
|RECORD=41|OwnerIndex=1270|IndexInSheet=-1|OwnerPartId=-1|Color=8388608|FontID=1|IsHidden=T|Text=2D|Name=Available Preview Images
|RECORD=45|OwnerIndex=1267|IndexInSheet=-1|Description=Chip Resistor, 2-Leads, Body 1.00x0.50mm, IPC High Density|UseComponentLibrary=T|ModelName=RESC1005X40X25LL05T05|ModelType=PCBLIB|DatafileCount=1|ModelDatafileEntity0=RESC1005X40X25LL05T05|ModelDatafileKind0=PCBLib|DatalinksLocked=T|DatabaseDatalinksLocked=T
|RECORD=46|OwnerIndex=1272
|RECORD=48|OwnerIndex=1272
|RECORD=41|OwnerIndex=1274|IndexInSheet=-1|OwnerPartId=-1|Color=8388608|FontID=1|IsHidden=T|Text=2D|Name=Available Preview Images
|RECORD=45|OwnerIndex=1267|IndexInSheet=-1|Description=Chip Resistor, 2-Leads, Body 1.00x0.50mm, IPC Low Density|UseComponentLibrary=T|ModelName=RESC1005X40X25ML05T05|ModelType=PCBLIB|DatafileCount=1|ModelDatafileEntity0=RESC1005X40X25ML05T05|ModelDatafileKind0=PCBLib|DatalinksLocked=T|DatabaseDatalinksLocked=T
|RECORD=46|OwnerIndex=1276
|RECORD=48|OwnerIndex=1276
|RECORD=41|OwnerIndex=1278|IndexInSheet=-1|OwnerPartId=-1|Color=8388608|FontID=1|IsHidden=T|Text=2D|Name=Available Preview Images
|RECORD=1|LibReference=RES|PartCount=2|DisplayModeCount=2|IndexInSheet=118|OwnerPartId=-1|Location.X=1310|Location.Y=360|CurrentPartId=1|SourceLibraryName=Altium Content Vault|TargetFileName=*|AreaColor=11599871|Color=128|PartIDLocked=F|DesignItemId=CMP-2002-08434-1|AllPinCount=2|ComponentKindVersion2=5
|RECORD=2|OwnerIndex=1280|OwnerPartId=1|OwnerPartDisplayMode=1|FormalType=1|Electrical=4|PinConglomerate=32|PinLength=10|Location.X=1330|Location.Y=350|Name=2|Designator=2|PinPropagationDelay=0.000000E+000
|RECORD=2|OwnerIndex=1280|OwnerPartId=1|OwnerPartDisplayMode=1|FormalType=1|Electrical=4|PinConglomerate=34|PinLength=10|Location.X=1310|Location.Y=350|Name=1|Designator=1|PinPropagationDelay=0.000000E+000
|RECORD=14|OwnerIndex=1280|IsNotAccesible=T|IndexInSheet=2|OwnerPartId=1|OwnerPartDisplayMode=1|Location.X=1310|Location.Y=346|Corner.X=1330|Corner.Y=354|LineWidth=1|Color=16711680|AreaColor=11599871
|RECORD=2|OwnerIndex=1280|OwnerPartId=1|FormalType=1|Electrical=4|PinConglomerate=32|PinLength=10|Location.X=1330|Location.Y=350|Name=2|Designator=2|PinPropagationDelay=0.000000E+000
|RECORD=2|OwnerIndex=1280|OwnerPartId=1|FormalType=1|Electrical=4|PinConglomerate=34|PinLength=10|Location.X=1310|Location.Y=350|Name=1|Designator=1|PinPropagationDelay=0.000000E+000
|RECORD=6|OwnerIndex=1280|IsNotAccesible=T|IndexInSheet=5|OwnerPartId=1|LineWidth=1|Color=16711680|LocationCount=10|X1=1330|Y1=350|X2=1326|Y2=350|X3=1325|Y3=348|X4=1323|Y4=352|X5=1321|Y5=348|X6=1319|Y6=352|X7=1317|Y7=348|X8=1315|Y8=352|X9=1314|Y9=350|X10=1310|Y10=350
|RECORD=41|OwnerIndex=1280|IndexInSheet=6|OwnerPartId=-1|Location.X=1298|Location.Y=363|Color=8388608|FontID=1|IsHidden=T|Text=CRCW040227R0FKED|Name=Part Number
|RECORD=41|OwnerIndex=1280|IndexInSheet=7|OwnerPartId=-1|Location.X=1298|Location.Y=363|Color=8388608|FontID=1|IsHidden=T|Text=Vishay Dale|Name=Manufacturer
|RECORD=34|OwnerIndex=1280|IndexInSheet=-1|OwnerPartId=-1|Location.X=1290|Location.Y=350|Color=8388608|FontID=1|Text=R103|Name=Designator|ReadOnlyState=1
|RECORD=41|OwnerIndex=1280|IndexInSheet=-1|OwnerPartId=-1|Location.X=1310|Location.Y=350|Color=8388608|FontID=1|Text=DNI_27_1%_0402|Name=Comment
|RECORD=44|OwnerIndex=1280
|RECORD=45|OwnerIndex=1295|IndexInSheet=-1|Description=Chip Resistor, 2-Leads, Body 1.00x0.50mm, IPC Medium Density|UseComponentLibrary=T|ModelName=RESC1005X40X25NL05T05|ModelType=PCBLIB|DatafileCount=1|ModelDatafileEntity0=RESC1005X40X25NL05T05|ModelDatafileKind0=PCBLib|IsCurrent=T|DatalinksLocked=T|DatabaseDatalinksLocked=T
|RECORD=46|OwnerIndex=1296
|RECORD=48|OwnerIndex=1296
|RECORD=41|OwnerIndex=1298|IndexInSheet=-1|OwnerPartId=-1|Color=8388608|FontID=1|IsHidden=T|Text=2D|Name=Available Preview Images
|RECORD=45|OwnerIndex=1295|IndexInSheet=-1|Description=Chip Resistor, 2-Leads, Body 1.00x0.50mm, IPC High Density|UseComponentLibrary=T|ModelName=RESC1005X40X25LL05T05|ModelType=PCBLIB|DatafileCount=1|ModelDatafileEntity0=RESC1005X40X25LL05T05|ModelDatafileKind0=PCBLib|DatalinksLocked=T|DatabaseDatalinksLocked=T
|RECORD=46|OwnerIndex=1300
|RECORD=48|OwnerIndex=1300
|RECORD=41|OwnerIndex=1302|IndexInSheet=-1|OwnerPartId=-1|Color=8388608|FontID=1|IsHidden=T|Text=2D|Name=Available Preview Images
|RECORD=45|OwnerIndex=1295|IndexInSheet=-1|Description=Chip Resistor, 2-Leads, Body 1.00x0.50mm, IPC Low Density|UseComponentLibrary=T|ModelName=RESC1005X40X25ML05T05|ModelType=PCBLIB|DatafileCount=1|ModelDatafileEntity0=RESC1005X40X25ML05T05|ModelDatafileKind0=PCBLib|DatalinksLocked=T|DatabaseDatalinksLocked=T
|RECORD=46|OwnerIndex=1304
|RECORD=48|OwnerIndex=1304
|RECORD=41|OwnerIndex=1306|IndexInSheet=-1|OwnerPartId=-1|Color=8388608|FontID=1|IsHidden=T|Text=2D|Name=Available Preview Images
|RECORD=17|IndexInSheet=119|OwnerPartId=-1|ShowNetName=T|Location.X=1280|Location.Y=350|Orientation=2|Color=255|FontID=1|Text=GPS2_RX_FPGA|IsCrossSheetConnector=T
|RECORD=17|IndexInSheet=120|OwnerPartId=-1|ShowNetName=T|Location.X=1280|Location.Y=380|Orientation=2|Color=255|FontID=1|Text=GPS2_TX_FPGA|IsCrossSheetConnector=T
|RECORD=1|LibReference=RES|PartCount=2|DisplayModeCount=2|IndexInSheet=121|OwnerPartId=-1|Location.X=1290|Location.Y=910|CurrentPartId=1|SourceLibraryName=Altium Content Vault|TargetFileName=*|AreaColor=11599871|Color=128|PartIDLocked=F|DesignItemId=CMP-2002-08434-1|AllPinCount=2|ComponentKindVersion2=5
|RECORD=2|OwnerIndex=1310|OwnerPartId=1|OwnerPartDisplayMode=1|FormalType=1|Electrical=4|PinConglomerate=32|PinLength=10|Location.X=1310|Location.Y=900|Name=2|Designator=2|PinPropagationDelay=0.000000E+000
|RECORD=2|OwnerIndex=1310|OwnerPartId=1|OwnerPartDisplayMode=1|FormalType=1|Electrical=4|PinConglomerate=34|PinLength=10|Location.X=1290|Location.Y=900|Name=1|Designator=1|PinPropagationDelay=0.000000E+000
|RECORD=14|OwnerIndex=1310|IsNotAccesible=T|IndexInSheet=2|OwnerPartId=1|OwnerPartDisplayMode=1|Location.X=1290|Location.Y=896|Corner.X=1310|Corner.Y=904|LineWidth=1|Color=16711680|AreaColor=11599871
|RECORD=2|OwnerIndex=1310|OwnerPartId=1|FormalType=1|Electrical=4|PinConglomerate=32|PinLength=10|Location.X=1310|Location.Y=900|Name=2|Designator=2|PinPropagationDelay=0.000000E+000
|RECORD=2|OwnerIndex=1310|OwnerPartId=1|FormalType=1|Electrical=4|PinConglomerate=34|PinLength=10|Location.X=1290|Location.Y=900|Name=1|Designator=1|PinPropagationDelay=0.000000E+000
|RECORD=6|OwnerIndex=1310|IsNotAccesible=T|IndexInSheet=5|OwnerPartId=1|LineWidth=1|Color=16711680|LocationCount=10|X1=1310|Y1=900|X2=1306|Y2=900|X3=1305|Y3=898|X4=1303|Y4=902|X5=1301|Y5=898|X6=1299|Y6=902|X7=1297|Y7=898|X8=1295|Y8=902|X9=1294|Y9=900|X10=1290|Y10=900
|RECORD=41|OwnerIndex=1310|IndexInSheet=6|OwnerPartId=-1|Location.X=1278|Location.Y=913|Color=8388608|FontID=1|IsHidden=T|Text=CRCW040227R0FKED|Name=Part Number
|RECORD=41|OwnerIndex=1310|IndexInSheet=7|OwnerPartId=-1|Location.X=1278|Location.Y=913|Color=8388608|FontID=1|IsHidden=T|Text=Vishay Dale|Name=Manufacturer
|RECORD=34|OwnerIndex=1310|IndexInSheet=-1|OwnerPartId=-1|Location.X=1270|Location.Y=900|Color=8388608|FontID=1|Text=R100|Name=Designator|ReadOnlyState=1
|RECORD=41|OwnerIndex=1310|IndexInSheet=-1|OwnerPartId=-1|Location.X=1290|Location.Y=900|Color=8388608|FontID=1|Text=DNI_27_1%_0402|Name=Comment
|RECORD=44|OwnerIndex=1310
|RECORD=45|OwnerIndex=1325|IndexInSheet=-1|Description=Chip Resistor, 2-Leads, Body 1.00x0.50mm, IPC Medium Density|UseComponentLibrary=T|ModelName=RESC1005X40X25NL05T05|ModelType=PCBLIB|DatafileCount=1|ModelDatafileEntity0=RESC1005X40X25NL05T05|ModelDatafileKind0=PCBLib|IsCurrent=T|DatalinksLocked=T|DatabaseDatalinksLocked=T
|RECORD=46|OwnerIndex=1326
|RECORD=48|OwnerIndex=1326
|RECORD=41|OwnerIndex=1328|IndexInSheet=-1|OwnerPartId=-1|Color=8388608|FontID=1|IsHidden=T|Text=2D|Name=Available Preview Images
|RECORD=45|OwnerIndex=1325|IndexInSheet=-1|Description=Chip Resistor, 2-Leads, Body 1.00x0.50mm, IPC High Density|UseComponentLibrary=T|ModelName=RESC1005X40X25LL05T05|ModelType=PCBLIB|DatafileCount=1|ModelDatafileEntity0=RESC1005X40X25LL05T05|ModelDatafileKind0=PCBLib|DatalinksLocked=T|DatabaseDatalinksLocked=T
|RECORD=46|OwnerIndex=1330
|RECORD=48|OwnerIndex=1330
|RECORD=41|OwnerIndex=1332|IndexInSheet=-1|OwnerPartId=-1|Color=8388608|FontID=1|IsHidden=T|Text=2D|Name=Available Preview Images
|RECORD=45|OwnerIndex=1325|IndexInSheet=-1|Description=Chip Resistor, 2-Leads, Body 1.00x0.50mm, IPC Low Density|UseComponentLibrary=T|ModelName=RESC1005X40X25ML05T05|ModelType=PCBLIB|DatafileCount=1|ModelDatafileEntity0=RESC1005X40X25ML05T05|ModelDatafileKind0=PCBLib|DatalinksLocked=T|DatabaseDatalinksLocked=T
|RECORD=46|OwnerIndex=1334
|RECORD=48|OwnerIndex=1334
|RECORD=41|OwnerIndex=1336|IndexInSheet=-1|OwnerPartId=-1|Color=8388608|FontID=1|IsHidden=T|Text=2D|Name=Available Preview Images
|RECORD=1|LibReference=RES|PartCount=2|DisplayModeCount=2|IndexInSheet=122|OwnerPartId=-1|Location.X=1290|Location.Y=890|CurrentPartId=1|SourceLibraryName=Altium Content Vault|TargetFileName=*|AreaColor=11599871|Color=128|PartIDLocked=F|DesignItemId=CMP-2002-08434-1|AllPinCount=2|ComponentKindVersion2=5
|RECORD=2|OwnerIndex=1338|OwnerPartId=1|OwnerPartDisplayMode=1|FormalType=1|Electrical=4|PinConglomerate=32|PinLength=10|Location.X=1310|Location.Y=880|Name=2|Designator=2|PinPropagationDelay=0.000000E+000
|RECORD=2|OwnerIndex=1338|OwnerPartId=1|OwnerPartDisplayMode=1|FormalType=1|Electrical=4|PinConglomerate=34|PinLength=10|Location.X=1290|Location.Y=880|Name=1|Designator=1|PinPropagationDelay=0.000000E+000
|RECORD=14|OwnerIndex=1338|IsNotAccesible=T|IndexInSheet=2|OwnerPartId=1|OwnerPartDisplayMode=1|Location.X=1290|Location.Y=876|Corner.X=1310|Corner.Y=884|LineWidth=1|Color=16711680|AreaColor=11599871
|RECORD=2|OwnerIndex=1338|OwnerPartId=1|FormalType=1|Electrical=4|PinConglomerate=32|PinLength=10|Location.X=1310|Location.Y=880|Name=2|Designator=2|PinPropagationDelay=0.000000E+000
|RECORD=2|OwnerIndex=1338|OwnerPartId=1|FormalType=1|Electrical=4|PinConglomerate=34|PinLength=10|Location.X=1290|Location.Y=880|Name=1|Designator=1|PinPropagationDelay=0.000000E+000
|RECORD=6|OwnerIndex=1338|IsNotAccesible=T|IndexInSheet=5|OwnerPartId=1|LineWidth=1|Color=16711680|LocationCount=10|X1=1310|Y1=880|X2=1306|Y2=880|X3=1305|Y3=878|X4=1303|Y4=882|X5=1301|Y5=878|X6=1299|Y6=882|X7=1297|Y7=878|X8=1295|Y8=882|X9=1294|Y9=880|X10=1290|Y10=880
|RECORD=41|OwnerIndex=1338|IndexInSheet=6|OwnerPartId=-1|Location.X=1278|Location.Y=893|Color=8388608|FontID=1|IsHidden=T|Text=CRCW040227R0FKED|Name=Part Number
|RECORD=41|OwnerIndex=1338|IndexInSheet=7|OwnerPartId=-1|Location.X=1278|Location.Y=893|Color=8388608|FontID=1|IsHidden=T|Text=Vishay Dale|Name=Manufacturer
|RECORD=34|OwnerIndex=1338|IndexInSheet=-1|OwnerPartId=-1|Location.X=1270|Location.Y=880|Color=8388608|FontID=1|Text=R101|Name=Designator|ReadOnlyState=1
|RECORD=41|OwnerIndex=1338|IndexInSheet=-1|OwnerPartId=-1|Location.X=1290|Location.Y=880|Color=8388608|FontID=1|Text=DNI_27_1%_0402|Name=Comment
|RECORD=44|OwnerIndex=1338
|RECORD=45|OwnerIndex=1353|IndexInSheet=-1|Description=Chip Resistor, 2-Leads, Body 1.00x0.50mm, IPC Medium Density|UseComponentLibrary=T|ModelName=RESC1005X40X25NL05T05|ModelType=PCBLIB|DatafileCount=1|ModelDatafileEntity0=RESC1005X40X25NL05T05|ModelDatafileKind0=PCBLib|IsCurrent=T|DatalinksLocked=T|DatabaseDatalinksLocked=T
|RECORD=46|OwnerIndex=1354
|RECORD=48|OwnerIndex=1354
|RECORD=41|OwnerIndex=1356|IndexInSheet=-1|OwnerPartId=-1|Color=8388608|FontID=1|IsHidden=T|Text=2D|Name=Available Preview Images
|RECORD=45|OwnerIndex=1353|IndexInSheet=-1|Description=Chip Resistor, 2-Leads, Body 1.00x0.50mm, IPC High Density|UseComponentLibrary=T|ModelName=RESC1005X40X25LL05T05|ModelType=PCBLIB|DatafileCount=1|ModelDatafileEntity0=RESC1005X40X25LL05T05|ModelDatafileKind0=PCBLib|DatalinksLocked=T|DatabaseDatalinksLocked=T
|RECORD=46|OwnerIndex=1358
|RECORD=48|OwnerIndex=1358
|RECORD=41|OwnerIndex=1360|IndexInSheet=-1|OwnerPartId=-1|Color=8388608|FontID=1|IsHidden=T|Text=2D|Name=Available Preview Images
|RECORD=45|OwnerIndex=1353|IndexInSheet=-1|Description=Chip Resistor, 2-Leads, Body 1.00x0.50mm, IPC Low Density|UseComponentLibrary=T|ModelName=RESC1005X40X25ML05T05|ModelType=PCBLIB|DatafileCount=1|ModelDatafileEntity0=RESC1005X40X25ML05T05|ModelDatafileKind0=PCBLib|DatalinksLocked=T|DatabaseDatalinksLocked=T
|RECORD=46|OwnerIndex=1362
|RECORD=48|OwnerIndex=1362
|RECORD=41|OwnerIndex=1364|IndexInSheet=-1|OwnerPartId=-1|Color=8388608|FontID=1|IsHidden=T|Text=2D|Name=Available Preview Images
|RECORD=17|IndexInSheet=123|OwnerPartId=-1|Style=1|ShowNetName=T|Location.X=1250|Location.Y=900|Orientation=2|Color=255|FontID=1|Text=FTDI_RX|IsCrossSheetConnector=T
|RECORD=17|IndexInSheet=124|OwnerPartId=-1|ShowNetName=T|Location.X=1250|Location.Y=880|Orientation=2|Color=255|FontID=1|Text=FTDI_TX|IsCrossSheetConnector=T
|RECORD=1|LibReference=RES|PartCount=2|DisplayModeCount=2|IndexInSheet=125|OwnerPartId=-1|Location.X=680|Location.Y=330|CurrentPartId=1|SourceLibraryName=Altium Content Vault|TargetFileName=*|AreaColor=11599871|Color=128|PartIDLocked=F|DesignItemId=CMP-2002-07709-1|AllPinCount=2|ComponentKindVersion2=5
|RECORD=2|OwnerIndex=1368|OwnerPartId=1|OwnerPartDisplayMode=1|FormalType=1|Electrical=4|PinConglomerate=32|PinLength=10|Location.X=700|Location.Y=320|Name=2|Designator=2|PinPropagationDelay=0.000000E+000
|RECORD=2|OwnerIndex=1368|OwnerPartId=1|OwnerPartDisplayMode=1|FormalType=1|Electrical=4|PinConglomerate=34|PinLength=10|Location.X=680|Location.Y=320|Name=1|Designator=1|PinPropagationDelay=0.000000E+000
|RECORD=14|OwnerIndex=1368|IsNotAccesible=T|IndexInSheet=2|OwnerPartId=1|OwnerPartDisplayMode=1|Location.X=680|Location.Y=316|Corner.X=700|Corner.Y=324|LineWidth=1|Color=16711680|AreaColor=11599871
|RECORD=2|OwnerIndex=1368|OwnerPartId=1|FormalType=1|Electrical=4|PinConglomerate=32|PinLength=10|Location.X=700|Location.Y=320|Name=2|Designator=2|PinPropagationDelay=0.000000E+000
|RECORD=2|OwnerIndex=1368|OwnerPartId=1|FormalType=1|Electrical=4|PinConglomerate=34|PinLength=10|Location.X=680|Location.Y=320|Name=1|Designator=1|PinPropagationDelay=0.000000E+000
|RECORD=6|OwnerIndex=1368|IsNotAccesible=T|IndexInSheet=5|OwnerPartId=1|LineWidth=1|Color=16711680|LocationCount=10|X1=700|Y1=320|X2=696|Y2=320|X3=695|Y3=318|X4=693|Y4=322|X5=691|Y5=318|X6=689|Y6=322|X7=687|Y7=318|X8=685|Y8=322|X9=684|Y9=320|X10=680|Y10=320
|RECORD=41|OwnerIndex=1368|IndexInSheet=6|OwnerPartId=-1|Location.X=668|Location.Y=333|Color=8388608|FontID=1|IsHidden=T|Text=Yageo / Phycomp|Name=Manufacturer
|RECORD=41|OwnerIndex=1368|IndexInSheet=7|OwnerPartId=-1|Location.X=668|Location.Y=333|Color=8388608|FontID=1|IsHidden=T|Text=RC0402FR-0749R9L|Name=Part Number
|RECORD=34|OwnerIndex=1368|IndexInSheet=-1|OwnerPartId=-1|Location.X=660|Location.Y=320|Color=8388608|FontID=1|Text=R107|Name=Designator|ReadOnlyState=1
|RECORD=41|OwnerIndex=1368|IndexInSheet=-1|OwnerPartId=-1|Location.X=700|Location.Y=320|Color=8388608|FontID=1|Text=DNI_49.9_1%_0402|Name=Comment
|RECORD=44|OwnerIndex=1368
|RECORD=45|OwnerIndex=1383|IndexInSheet=-1|Description=Chip Resistor, 2-Leads, Body 1.00x0.50mm, IPC High Density|UseComponentLibrary=T|ModelName=RESC1005X40X25LL05T10|ModelType=PCBLIB|DatafileCount=1|ModelDatafileEntity0=RESC1005X40X25LL05T10|ModelDatafileKind0=PCBLib|IsCurrent=T|DatalinksLocked=T|DatabaseDatalinksLocked=T
|RECORD=46|OwnerIndex=1384
|RECORD=48|OwnerIndex=1384
|RECORD=41|OwnerIndex=1386|IndexInSheet=-1|OwnerPartId=-1|Color=8388608|FontID=1|IsHidden=T|Text=2D|Name=Available Preview Images
|RECORD=45|OwnerIndex=1383|IndexInSheet=-1|Description=Chip Resistor, 2-Leads, Body 1.00x0.50mm, IPC Low Density|UseComponentLibrary=T|ModelName=RESC1005X40X25ML05T10|ModelType=PCBLIB|DatafileCount=1|ModelDatafileEntity0=RESC1005X40X25ML05T10|ModelDatafileKind0=PCBLib|DatalinksLocked=T|DatabaseDatalinksLocked=T
|RECORD=46|OwnerIndex=1388
|RECORD=48|OwnerIndex=1388
|RECORD=41|OwnerIndex=1390|IndexInSheet=-1|OwnerPartId=-1|Color=8388608|FontID=1|IsHidden=T|Text=2D|Name=Available Preview Images
|RECORD=45|OwnerIndex=1383|IndexInSheet=-1|Description=Chip Resistor, 2-Leads, Body 1.00x0.50mm, IPC Medium Density|UseComponentLibrary=T|ModelName=RESC1005X40X25NL05T10|ModelType=PCBLIB|DatafileCount=1|ModelDatafileEntity0=RESC1005X40X25NL05T10|ModelDatafileKind0=PCBLib|DatalinksLocked=T|DatabaseDatalinksLocked=T
|RECORD=46|OwnerIndex=1392
|RECORD=48|OwnerIndex=1392
|RECORD=41|OwnerIndex=1394|IndexInSheet=-1|OwnerPartId=-1|Color=8388608|FontID=1|IsHidden=T|Text=2D|Name=Available Preview Images
|RECORD=1|LibReference=RES|PartCount=2|DisplayModeCount=2|IndexInSheet=126|OwnerPartId=-1|Location.X=680|Location.Y=350|CurrentPartId=1|SourceLibraryName=Altium Content Vault|TargetFileName=*|AreaColor=11599871|Color=128|PartIDLocked=F|DesignItemId=CMP-2002-07709-1|AllPinCount=2|ComponentKindVersion2=5
|RECORD=2|OwnerIndex=1396|OwnerPartId=1|OwnerPartDisplayMode=1|FormalType=1|Electrical=4|PinConglomerate=32|PinLength=10|Location.X=700|Location.Y=340|Name=2|Designator=2|PinPropagationDelay=0.000000E+000
|RECORD=2|OwnerIndex=1396|OwnerPartId=1|OwnerPartDisplayMode=1|FormalType=1|Electrical=4|PinConglomerate=34|PinLength=10|Location.X=680|Location.Y=340|Name=1|Designator=1|PinPropagationDelay=0.000000E+000
|RECORD=14|OwnerIndex=1396|IsNotAccesible=T|IndexInSheet=2|OwnerPartId=1|OwnerPartDisplayMode=1|Location.X=680|Location.Y=336|Corner.X=700|Corner.Y=344|LineWidth=1|Color=16711680|AreaColor=11599871
|RECORD=2|OwnerIndex=1396|OwnerPartId=1|FormalType=1|Electrical=4|PinConglomerate=32|PinLength=10|Location.X=700|Location.Y=340|Name=2|Designator=2|PinPropagationDelay=0.000000E+000
|RECORD=2|OwnerIndex=1396|OwnerPartId=1|FormalType=1|Electrical=4|PinConglomerate=34|PinLength=10|Location.X=680|Location.Y=340|Name=1|Designator=1|PinPropagationDelay=0.000000E+000
|RECORD=6|OwnerIndex=1396|IsNotAccesible=T|IndexInSheet=5|OwnerPartId=1|LineWidth=1|Color=16711680|LocationCount=10|X1=700|Y1=340|X2=696|Y2=340|X3=695|Y3=338|X4=693|Y4=342|X5=691|Y5=338|X6=689|Y6=342|X7=687|Y7=338|X8=685|Y8=342|X9=684|Y9=340|X10=680|Y10=340
|RECORD=41|OwnerIndex=1396|IndexInSheet=6|OwnerPartId=-1|Location.X=668|Location.Y=353|Color=8388608|FontID=1|IsHidden=T|Text=Yageo / Phycomp|Name=Manufacturer
|RECORD=41|OwnerIndex=1396|IndexInSheet=7|OwnerPartId=-1|Location.X=668|Location.Y=353|Color=8388608|FontID=1|IsHidden=T|Text=RC0402FR-0749R9L|Name=Part Number
|RECORD=34|OwnerIndex=1396|IndexInSheet=-1|OwnerPartId=-1|Location.X=660|Location.Y=340|Color=8388608|FontID=1|Text=R105|Name=Designator|ReadOnlyState=1
|RECORD=41|OwnerIndex=1396|IndexInSheet=-1|OwnerPartId=-1|Location.X=700|Location.Y=340|Color=8388608|FontID=1|Text=DNI_49.9_1%_0402|Name=Comment
|RECORD=44|OwnerIndex=1396
|RECORD=45|OwnerIndex=1411|IndexInSheet=-1|Description=Chip Resistor, 2-Leads, Body 1.00x0.50mm, IPC High Density|UseComponentLibrary=T|ModelName=RESC1005X40X25LL05T10|ModelType=PCBLIB|DatafileCount=1|ModelDatafileEntity0=RESC1005X40X25LL05T10|ModelDatafileKind0=PCBLib|IsCurrent=T|DatalinksLocked=T|DatabaseDatalinksLocked=T
|RECORD=46|OwnerIndex=1412
|RECORD=48|OwnerIndex=1412
|RECORD=41|OwnerIndex=1414|IndexInSheet=-1|OwnerPartId=-1|Color=8388608|FontID=1|IsHidden=T|Text=2D|Name=Available Preview Images
|RECORD=45|OwnerIndex=1411|IndexInSheet=-1|Description=Chip Resistor, 2-Leads, Body 1.00x0.50mm, IPC Low Density|UseComponentLibrary=T|ModelName=RESC1005X40X25ML05T10|ModelType=PCBLIB|DatafileCount=1|ModelDatafileEntity0=RESC1005X40X25ML05T10|ModelDatafileKind0=PCBLib|DatalinksLocked=T|DatabaseDatalinksLocked=T
|RECORD=46|OwnerIndex=1416
|RECORD=48|OwnerIndex=1416
|RECORD=41|OwnerIndex=1418|IndexInSheet=-1|OwnerPartId=-1|Color=8388608|FontID=1|IsHidden=T|Text=2D|Name=Available Preview Images
|RECORD=45|OwnerIndex=1411|IndexInSheet=-1|Description=Chip Resistor, 2-Leads, Body 1.00x0.50mm, IPC Medium Density|UseComponentLibrary=T|ModelName=RESC1005X40X25NL05T10|ModelType=PCBLIB|DatafileCount=1|ModelDatafileEntity0=RESC1005X40X25NL05T10|ModelDatafileKind0=PCBLib|DatalinksLocked=T|DatabaseDatalinksLocked=T
|RECORD=46|OwnerIndex=1420
|RECORD=48|OwnerIndex=1420
|RECORD=41|OwnerIndex=1422|IndexInSheet=-1|OwnerPartId=-1|Color=8388608|FontID=1|IsHidden=T|Text=2D|Name=Available Preview Images
|RECORD=1|LibReference=RES|PartCount=2|DisplayModeCount=2|IndexInSheet=127|OwnerPartId=-1|Location.X=680|Location.Y=360|CurrentPartId=1|SourceLibraryName=Altium Content Vault|TargetFileName=*|AreaColor=11599871|Color=128|PartIDLocked=F|DesignItemId=CMP-2002-07709-1|AllPinCount=2|ComponentKindVersion2=5
|RECORD=2|OwnerIndex=1424|OwnerPartId=1|OwnerPartDisplayMode=1|FormalType=1|Electrical=4|PinConglomerate=32|PinLength=10|Location.X=700|Location.Y=350|Name=2|Designator=2|PinPropagationDelay=0.000000E+000
|RECORD=2|OwnerIndex=1424|OwnerPartId=1|OwnerPartDisplayMode=1|FormalType=1|Electrical=4|PinConglomerate=34|PinLength=10|Location.X=680|Location.Y=350|Name=1|Designator=1|PinPropagationDelay=0.000000E+000
|RECORD=14|OwnerIndex=1424|IsNotAccesible=T|IndexInSheet=2|OwnerPartId=1|OwnerPartDisplayMode=1|Location.X=680|Location.Y=346|Corner.X=700|Corner.Y=354|LineWidth=1|Color=16711680|AreaColor=11599871
|RECORD=2|OwnerIndex=1424|OwnerPartId=1|FormalType=1|Electrical=4|PinConglomerate=32|PinLength=10|Location.X=700|Location.Y=350|Name=2|Designator=2|PinPropagationDelay=0.000000E+000
|RECORD=2|OwnerIndex=1424|OwnerPartId=1|FormalType=1|Electrical=4|PinConglomerate=34|PinLength=10|Location.X=680|Location.Y=350|Name=1|Designator=1|PinPropagationDelay=0.000000E+000
|RECORD=6|OwnerIndex=1424|IsNotAccesible=T|IndexInSheet=5|OwnerPartId=1|LineWidth=1|Color=16711680|LocationCount=10|X1=700|Y1=350|X2=696|Y2=350|X3=695|Y3=348|X4=693|Y4=352|X5=691|Y5=348|X6=689|Y6=352|X7=687|Y7=348|X8=685|Y8=352|X9=684|Y9=350|X10=680|Y10=350
|RECORD=41|OwnerIndex=1424|IndexInSheet=6|OwnerPartId=-1|Location.X=668|Location.Y=363|Color=8388608|FontID=1|IsHidden=T|Text=Yageo / Phycomp|Name=Manufacturer
|RECORD=41|OwnerIndex=1424|IndexInSheet=7|OwnerPartId=-1|Location.X=668|Location.Y=363|Color=8388608|FontID=1|IsHidden=T|Text=RC0402FR-0749R9L|Name=Part Number
|RECORD=34|OwnerIndex=1424|IndexInSheet=-1|OwnerPartId=-1|Location.X=660|Location.Y=350|Color=8388608|FontID=1|Text=R104|Name=Designator|ReadOnlyState=1
|RECORD=41|OwnerIndex=1424|IndexInSheet=-1|OwnerPartId=-1|Location.X=700|Location.Y=350|Color=8388608|FontID=1|Text=DNI_49.9_1%_0402|Name=Comment
|RECORD=44|OwnerIndex=1424
|RECORD=45|OwnerIndex=1439|IndexInSheet=-1|Description=Chip Resistor, 2-Leads, Body 1.00x0.50mm, IPC High Density|UseComponentLibrary=T|ModelName=RESC1005X40X25LL05T10|ModelType=PCBLIB|DatafileCount=1|ModelDatafileEntity0=RESC1005X40X25LL05T10|ModelDatafileKind0=PCBLib|IsCurrent=T|DatalinksLocked=T|DatabaseDatalinksLocked=T
|RECORD=46|OwnerIndex=1440
|RECORD=48|OwnerIndex=1440
|RECORD=41|OwnerIndex=1442|IndexInSheet=-1|OwnerPartId=-1|Color=8388608|FontID=1|IsHidden=T|Text=2D|Name=Available Preview Images
|RECORD=45|OwnerIndex=1439|IndexInSheet=-1|Description=Chip Resistor, 2-Leads, Body 1.00x0.50mm, IPC Low Density|UseComponentLibrary=T|ModelName=RESC1005X40X25ML05T10|ModelType=PCBLIB|DatafileCount=1|ModelDatafileEntity0=RESC1005X40X25ML05T10|ModelDatafileKind0=PCBLib|DatalinksLocked=T|DatabaseDatalinksLocked=T
|RECORD=46|OwnerIndex=1444
|RECORD=48|OwnerIndex=1444
|RECORD=41|OwnerIndex=1446|IndexInSheet=-1|OwnerPartId=-1|Color=8388608|FontID=1|IsHidden=T|Text=2D|Name=Available Preview Images
|RECORD=45|OwnerIndex=1439|IndexInSheet=-1|Description=Chip Resistor, 2-Leads, Body 1.00x0.50mm, IPC Medium Density|UseComponentLibrary=T|ModelName=RESC1005X40X25NL05T10|ModelType=PCBLIB|DatafileCount=1|ModelDatafileEntity0=RESC1005X40X25NL05T10|ModelDatafileKind0=PCBLib|DatalinksLocked=T|DatabaseDatalinksLocked=T
|RECORD=46|OwnerIndex=1448
|RECORD=48|OwnerIndex=1448
|RECORD=41|OwnerIndex=1450|IndexInSheet=-1|OwnerPartId=-1|Color=8388608|FontID=1|IsHidden=T|Text=2D|Name=Available Preview Images
|RECORD=17|IndexInSheet=128|OwnerPartId=-1|ShowNetName=T|Location.X=790|Location.Y=350|Color=255|FontID=1|Text=MAC_PPS_OUT|IsCrossSheetConnector=T
|RECORD=1|LibReference=RES|PartCount=2|DisplayModeCount=2|IndexInSheet=129|OwnerPartId=-1|Location.X=680|Location.Y=340|CurrentPartId=1|SourceLibraryName=Altium Content Vault|TargetFileName=*|AreaColor=11599871|Color=128|PartIDLocked=F|DesignItemId=CMP-2002-07709-1|AllPinCount=2|ComponentKindVersion2=5
|RECORD=2|OwnerIndex=1453|OwnerPartId=1|OwnerPartDisplayMode=1|FormalType=1|Electrical=4|PinConglomerate=32|PinLength=10|Location.X=700|Location.Y=330|Name=2|Designator=2|PinPropagationDelay=0.000000E+000
|RECORD=2|OwnerIndex=1453|OwnerPartId=1|OwnerPartDisplayMode=1|FormalType=1|Electrical=4|PinConglomerate=34|PinLength=10|Location.X=680|Location.Y=330|Name=1|Designator=1|PinPropagationDelay=0.000000E+000
|RECORD=14|OwnerIndex=1453|IsNotAccesible=T|IndexInSheet=2|OwnerPartId=1|OwnerPartDisplayMode=1|Location.X=680|Location.Y=326|Corner.X=700|Corner.Y=334|LineWidth=1|Color=16711680|AreaColor=11599871
|RECORD=2|OwnerIndex=1453|OwnerPartId=1|FormalType=1|Electrical=4|PinConglomerate=32|PinLength=10|Location.X=700|Location.Y=330|Name=2|Designator=2|PinPropagationDelay=0.000000E+000
|RECORD=2|OwnerIndex=1453|OwnerPartId=1|FormalType=1|Electrical=4|PinConglomerate=34|PinLength=10|Location.X=680|Location.Y=330|Name=1|Designator=1|PinPropagationDelay=0.000000E+000
|RECORD=6|OwnerIndex=1453|IsNotAccesible=T|IndexInSheet=5|OwnerPartId=1|LineWidth=1|Color=16711680|LocationCount=10|X1=700|Y1=330|X2=696|Y2=330|X3=695|Y3=328|X4=693|Y4=332|X5=691|Y5=328|X6=689|Y6=332|X7=687|Y7=328|X8=685|Y8=332|X9=684|Y9=330|X10=680|Y10=330
|RECORD=41|OwnerIndex=1453|IndexInSheet=6|OwnerPartId=-1|Location.X=668|Location.Y=343|Color=8388608|FontID=1|IsHidden=T|Text=Yageo / Phycomp|Name=Manufacturer
|RECORD=41|OwnerIndex=1453|IndexInSheet=7|OwnerPartId=-1|Location.X=668|Location.Y=343|Color=8388608|FontID=1|IsHidden=T|Text=RC0402FR-0749R9L|Name=Part Number
|RECORD=34|OwnerIndex=1453|IndexInSheet=-1|OwnerPartId=-1|Location.X=660|Location.Y=330|Color=8388608|FontID=1|Text=R106|Name=Designator|ReadOnlyState=1
|RECORD=41|OwnerIndex=1453|IndexInSheet=-1|OwnerPartId=-1|Location.X=700|Location.Y=330|Color=8388608|FontID=1|Text=DNI_49.9_1%_0402|Name=Comment
|RECORD=44|OwnerIndex=1453
|RECORD=45|OwnerIndex=1468|IndexInSheet=-1|Description=Chip Resistor, 2-Leads, Body 1.00x0.50mm, IPC High Density|UseComponentLibrary=T|ModelName=RESC1005X40X25LL05T10|ModelType=PCBLIB|DatafileCount=1|ModelDatafileEntity0=RESC1005X40X25LL05T10|ModelDatafileKind0=PCBLib|IsCurrent=T|DatalinksLocked=T|DatabaseDatalinksLocked=T
|RECORD=46|OwnerIndex=1469
|RECORD=48|OwnerIndex=1469
|RECORD=41|OwnerIndex=1471|IndexInSheet=-1|OwnerPartId=-1|Color=8388608|FontID=1|IsHidden=T|Text=2D|Name=Available Preview Images
|RECORD=45|OwnerIndex=1468|IndexInSheet=-1|Description=Chip Resistor, 2-Leads, Body 1.00x0.50mm, IPC Low Density|UseComponentLibrary=T|ModelName=RESC1005X40X25ML05T10|ModelType=PCBLIB|DatafileCount=1|ModelDatafileEntity0=RESC1005X40X25ML05T10|ModelDatafileKind0=PCBLib|DatalinksLocked=T|DatabaseDatalinksLocked=T
|RECORD=46|OwnerIndex=1473
|RECORD=48|OwnerIndex=1473
|RECORD=41|OwnerIndex=1475|IndexInSheet=-1|OwnerPartId=-1|Color=8388608|FontID=1|IsHidden=T|Text=2D|Name=Available Preview Images
|RECORD=45|OwnerIndex=1468|IndexInSheet=-1|Description=Chip Resistor, 2-Leads, Body 1.00x0.50mm, IPC Medium Density|UseComponentLibrary=T|ModelName=RESC1005X40X25NL05T10|ModelType=PCBLIB|DatafileCount=1|ModelDatafileEntity0=RESC1005X40X25NL05T10|ModelDatafileKind0=PCBLib|DatalinksLocked=T|DatabaseDatalinksLocked=T
|RECORD=46|OwnerIndex=1477
|RECORD=48|OwnerIndex=1477
|RECORD=41|OwnerIndex=1479|IndexInSheet=-1|OwnerPartId=-1|Color=8388608|FontID=1|IsHidden=T|Text=2D|Name=Available Preview Images
|RECORD=17|IndexInSheet=130|OwnerPartId=-1|ShowNetName=T|Location.X=790|Location.Y=340|Color=255|FontID=1|Text=FPGA_MAC_PPSDIFF_OUT|IsCrossSheetConnector=T
|RECORD=17|IndexInSheet=131|OwnerPartId=-1|Style=1|ShowNetName=T|Location.X=790|Location.Y=330|Color=255|FontID=1|Text=MAC_PPS_IN|IsCrossSheetConnector=T
|RECORD=17|IndexInSheet=132|OwnerPartId=-1|Style=1|ShowNetName=T|Location.X=790|Location.Y=320|Color=255|FontID=1|Text=FPGA_MAC_PPS_DIFF_IN0|IsCrossSheetConnector=T
|RECORD=1|LibReference=1029c3af85768c4190bb7ad29bc67b5|ComponentDescription=RES SMD 15K OHM 1% 1/10W 0402|PartCount=2|DisplayModeCount=1|IndexInSheet=133|OwnerPartId=-1|Location.X=490|Location.Y=690|Orientation=1|CurrentPartId=1|LibraryPath=*|SourceLibraryName=Altium Content Vault|TargetFileName=*|AreaColor=11599871|Color=128|PartIDLocked=T|DesignItemId=CMP-2002-00694-4|AllPinCount=2
|RECORD=2|OwnerIndex=1484|OwnerPartId=1|Electrical=4|PinConglomerate=51|PinLength=20|Location.X=490|Location.Y=710|Name=1|Designator=1|PinPropagationDelay=0.000000E+000
|RECORD=2|OwnerIndex=1484|OwnerPartId=1|Electrical=4|PinConglomerate=49|PinLength=20|Location.X=490|Location.Y=740|Name=2|Designator=2|PinPropagationDelay=0.000000E+000
|RECORD=13|OwnerIndex=1484|IsNotAccesible=T|IndexInSheet=2|OwnerPartId=1|Location.X=490|Location.Y=710|Corner.X=485|Corner.Y=713|LineWidth=1|Color=16711680
|RECORD=13|OwnerIndex=1484|IsNotAccesible=T|IndexInSheet=3|OwnerPartId=1|Location.X=485|Location.Y=713|Corner.X=495|Corner.Y=718|LineWidth=1|Color=16711680
|RECORD=13|OwnerIndex=1484|IsNotAccesible=T|IndexInSheet=4|OwnerPartId=1|Location.X=495|Location.Y=718|Corner.X=485|Corner.Y=723|LineWidth=1|Color=16711680
|RECORD=13|OwnerIndex=1484|IsNotAccesible=T|IndexInSheet=5|OwnerPartId=1|Location.X=485|Location.Y=723|Corner.X=495|Corner.Y=728|LineWidth=1|Color=16711680
|RECORD=13|OwnerIndex=1484|IsNotAccesible=T|IndexInSheet=6|OwnerPartId=1|Location.X=495|Location.Y=728|Corner.X=485|Corner.Y=733|LineWidth=1|Color=16711680
|RECORD=13|OwnerIndex=1484|IsNotAccesible=T|IndexInSheet=7|OwnerPartId=1|Location.X=485|Location.Y=733|Corner.X=495|Corner.Y=738|LineWidth=1|Color=16711680
|RECORD=13|OwnerIndex=1484|IsNotAccesible=T|IndexInSheet=8|OwnerPartId=1|Location.X=495|Location.Y=738|Corner.X=490|Corner.Y=740|LineWidth=1|Color=16711680
|RECORD=13|OwnerIndex=1484|IsNotAccesible=T|IndexInSheet=9|OwnerPartId=1|Location.X=490|Location.Y=710|Corner.X=490|Corner.Y=707|LineWidth=1|Color=16711680
|RECORD=13|OwnerIndex=1484|IsNotAccesible=T|IndexInSheet=10|OwnerPartId=1|Location.X=490|Location.Y=740|Corner.X=490|Corner.Y=743|LineWidth=1|Color=16711680
|RECORD=41|OwnerIndex=1484|IndexInSheet=11|OwnerPartId=-1|Location.X=484|Location.Y=762|Color=8388608|FontID=3|IsHidden=T|Text=https://industrial.panasonic.com/cdbs/www-data/pdf/RDA0000/AOA0000C304.pdf|Name=ComponentLink2URL
|RECORD=41|OwnerIndex=1484|IndexInSheet=12|OwnerPartId=-1|Location.X=484|Location.Y=762|Color=8388608|FontID=1|IsHidden=T|Text=Yes|Name=Automotive
|RECORD=41|OwnerIndex=1484|IndexInSheet=13|OwnerPartId=-1|Location.X=484|Location.Y=762|Color=8388608|FontID=1|IsHidden=T|Text=-55°C to +155°C|Name=Temperature
|RECORD=41|OwnerIndex=1484|IndexInSheet=14|OwnerPartId=-1|Location.X=484|Location.Y=762|Color=8388608|FontID=1|IsHidden=T|Text=0.4mm|Name=Height
|RECORD=41|OwnerIndex=1484|IndexInSheet=15|OwnerPartId=-1|Location.X=484|Location.Y=762|Color=8388608|FontID=1|IsHidden=T|Text=Grade 0|Name=Automotive Grade
|RECORD=41|OwnerIndex=1484|IndexInSheet=16|OwnerPartId=-1|Location.X=484|Location.Y=762|Color=8388608|FontID=1|IsHidden=T|Text=RES SMD 15K OHM 1% 1/10W 0402|Name=Digikey Description
|RECORD=41|OwnerIndex=1484|IndexInSheet=17|OwnerPartId=-1|Location.X=484|Location.Y=762|Color=8388608|FontID=1|IsHidden=T|Text=50V|Name=Voltage Rating
|RECORD=41|OwnerIndex=1484|IndexInSheet=18|OwnerPartId=-1|Location.X=484|Location.Y=762|Color=8388608|FontID=1|IsHidden=T|Text=Res|Name=Category
|RECORD=41|OwnerIndex=1484|IndexInSheet=19|OwnerPartId=-1|Location.X=484|Location.Y=762|Color=8388608|FontID=1|IsHidden=T|Text=Resistors|Name=Device Class L2
|RECORD=41|OwnerIndex=1484|IndexInSheet=20|OwnerPartId=-1|Location.X=484|Location.Y=762|Color=8388608|FontID=1|IsHidden=T|Text=Passive Components|Name=Device Class L1
|RECORD=41|OwnerIndex=1484|IndexInSheet=21|OwnerPartId=-1|Location.X=484|Location.Y=762|Color=8388608|FontID=1|IsHidden=T|Text=ERJ2R|Name=Package
|RECORD=41|OwnerIndex=1484|IndexInSheet=22|OwnerPartId=-1|Location.X=484|Location.Y=762|Color=8388608|FontID=1|IsHidden=T|Text=-55°C|Name=Temperature Range Low
|RECORD=41|OwnerIndex=1484|IndexInSheet=23|OwnerPartId=-1|Location.X=484|Location.Y=762|Color=8388608|FontID=1|IsHidden=T|Text=1%|Name=Tolerance
|RECORD=41|OwnerIndex=1484|IndexInSheet=24|OwnerPartId=-1|Location.X=484|Location.Y=762|Color=8388608|FontID=1|IsHidden=T|Text=ERJ|Name=Series
|RECORD=41|OwnerIndex=1484|IndexInSheet=25|OwnerPartId=-1|Location.X=484|Location.Y=762|Color=8388608|FontID=1|IsHidden=T|Text=ERJ-2RKF1502X|Name=Manufacturer Part Number
|RECORD=41|OwnerIndex=1484|IndexInSheet=26|OwnerPartId=-1|Location.X=484|Location.Y=762|Color=8388608|FontID=3|IsHidden=T|Text=https://b2b-api.panasonic.eu/file_stream/pids/fileversion/1180|Name=Footprint Url
|RECORD=41|OwnerIndex=1484|IndexInSheet=27|OwnerPartId=-1|Location.X=484|Location.Y=762|Color=8388608|FontID=1|IsHidden=T|Text=Res Thick Film 1.0 x 0.5 mm 15K Ohm 1% 0.1W(1/10W) 100ppm/ C Molded SMD Punched Carrier T/R|Name=Mouser Description
|RECORD=41|OwnerIndex=1484|IndexInSheet=28|OwnerPartId=-1|Location.X=484|Location.Y=762|Color=8388608|FontID=1|IsHidden=T|Text=Thick Film|Name=Composition
|RECORD=41|OwnerIndex=1484|IndexInSheet=29|OwnerPartId=-1|Location.X=484|Location.Y=762|Color=8388608|FontID=1|IsHidden=T|Text=Yes|Name=Lead Free
|RECORD=41|OwnerIndex=1484|IndexInSheet=30|OwnerPartId=-1|Location.X=484|Location.Y=762|Color=8388608|FontID=1|IsHidden=T|Text=Chip SMD Resistors|Name=Device Class L3
|RECORD=41|OwnerIndex=1484|IndexInSheet=31|OwnerPartId=-1|Location.X=484|Location.Y=762|Color=8388608|FontID=1|IsHidden=T|Text=15kO|Name=Resistance
|RECORD=41|OwnerIndex=1484|IndexInSheet=32|OwnerPartId=-1|Location.X=484|Location.Y=762|Color=8388608|FontID=3|IsHidden=T|Text=https://octopart.com/erj-2rkf1502x-panasonic-55404985|Name=Octopart
|RECORD=41|OwnerIndex=1484|IndexInSheet=33|OwnerPartId=-1|Location.X=484|Location.Y=762|Color=8388608|FontID=1|IsHidden=T|Text=TRUE|Name=RoHS
|RECORD=41|OwnerIndex=1484|IndexInSheet=34|OwnerPartId=-1|Location.X=484|Location.Y=762|Color=8388608|FontID=1|IsHidden=T|Text=100ppm/°C|Name=Temperature Coefficient
|RECORD=41|OwnerIndex=1484|IndexInSheet=35|OwnerPartId=-1|Location.X=484|Location.Y=762|Color=8388608|FontID=1|IsHidden=T|Text=0.1W|Name=Power Rating
|RECORD=41|OwnerIndex=1484|IndexInSheet=36|OwnerPartId=-1|Location.X=484|Location.Y=762|Color=8388608|FontID=1|IsHidden=T|Text=Panasonic|Name=Manufacturer
|RECORD=41|OwnerIndex=1484|IndexInSheet=37|OwnerPartId=-1|Location.X=484|Location.Y=762|Color=8388608|FontID=1|IsHidden=T|Text=15kO|Name=Value
|RECORD=41|OwnerIndex=1484|IndexInSheet=38|OwnerPartId=-1|Location.X=484|Location.Y=762|Color=8388608|FontID=1|IsHidden=T|Text=+155°C|Name=Temperature Range High
|RECORD=41|OwnerIndex=1484|IndexInSheet=39|OwnerPartId=-1|Location.X=484|Location.Y=762|Color=8388608|FontID=1|IsHidden=T|Text=Datasheet|Name=ComponentLink2Description
|RECORD=34|OwnerIndex=1484|IndexInSheet=-1|OwnerPartId=-1|Location.X=480|Location.Y=700|Orientation=1|Color=8388608|FontID=2|Text=R83|Name=Designator|ReadOnlyState=1
|RECORD=41|OwnerIndex=1484|IndexInSheet=-1|OwnerPartId=1|Location.X=510|Location.Y=700|Orientation=1|Color=8388608|FontID=2|Text=15K_1%_0402|Name=Comment
|RECORD=44|OwnerIndex=1484
|RECORD=45|OwnerIndex=1529|IndexInSheet=-1|UseComponentLibrary=T|ModelName=FP-ERJ2R-MFG|ModelType=PCBLIB|DatafileCount=1|ModelDatafileEntity0=FP-ERJ2R-MFG|ModelDatafileKind0=PCBLib|IsCurrent=T|DatalinksLocked=T|DatabaseDatalinksLocked=T
|RECORD=46|OwnerIndex=1530
|RECORD=48|OwnerIndex=1530
|RECORD=45|OwnerIndex=1529|IndexInSheet=-1|UseComponentLibrary=T|ModelName=FP-ERJ2R-IPC_C|ModelType=PCBLIB|DatafileCount=1|ModelDatafileEntity0=FP-ERJ2R-IPC_C|ModelDatafileKind0=PCBLib|DatalinksLocked=T|DatabaseDatalinksLocked=T
|RECORD=46|OwnerIndex=1533
|RECORD=48|OwnerIndex=1533
|RECORD=45|OwnerIndex=1529|IndexInSheet=-1|UseComponentLibrary=T|ModelName=FP-ERJ2R-IPC_B|ModelType=PCBLIB|DatafileCount=1|ModelDatafileEntity0=FP-ERJ2R-IPC_B|ModelDatafileKind0=PCBLib|DatalinksLocked=T|DatabaseDatalinksLocked=T
|RECORD=46|OwnerIndex=1536
|RECORD=48|OwnerIndex=1536
|RECORD=45|OwnerIndex=1529|IndexInSheet=-1|UseComponentLibrary=T|ModelName=FP-ERJ2R-IPC_A|ModelType=PCBLIB|DatafileCount=1|ModelDatafileEntity0=FP-ERJ2R-IPC_A|ModelDatafileKind0=PCBLib|DatalinksLocked=T|DatabaseDatalinksLocked=T
|RECORD=46|OwnerIndex=1539
|RECORD=48|OwnerIndex=1539
|RECORD=1|LibReference=CAP|PartCount=2|DisplayModeCount=2|IndexInSheet=134|OwnerPartId=-1|Location.X=250|Location.Y=750|Orientation=1|CurrentPartId=1|SourceLibraryName=Altium Content Vault|TargetFileName=*|AreaColor=11599871|Color=128|PartIDLocked=F|DesignItemId=CMP-2008-04368-1|AllPinCount=2
|RECORD=2|OwnerIndex=1542|OwnerPartId=1|OwnerPartDisplayMode=1|FormalType=1|Electrical=4|PinConglomerate=35|PinLength=10|Location.X=260|Location.Y=750|Name=1|Designator=1|PinPropagationDelay=0.000000E+000
|RECORD=2|OwnerIndex=1542|OwnerPartId=1|OwnerPartDisplayMode=1|FormalType=1|Electrical=4|PinConglomerate=33|PinLength=10|Location.X=260|Location.Y=760|Name=2|Designator=2|PinPropagationDelay=0.000000E+000
|RECORD=13|OwnerIndex=1542|IsNotAccesible=T|IndexInSheet=2|OwnerPartId=1|OwnerPartDisplayMode=1|Location.X=268|Location.Y=750|Corner.X=252|Corner.Y=750|LineWidth=1|Color=16711680
|RECORD=13|OwnerIndex=1542|IsNotAccesible=T|IndexInSheet=3|OwnerPartId=1|OwnerPartDisplayMode=1|Location.X=260|Location.Y=754|Corner.X=260|Corner.Y=760|LineWidth=1|Color=16711680
|RECORD=12|OwnerIndex=1542|IsNotAccesible=T|IndexInSheet=4|OwnerPartId=1|OwnerPartDisplayMode=1|Location.X=260|Location.Y=770|Radius=16|LineWidth=1|StartAngle=241.000|EndAngle=270.000|Color=16711680
|RECORD=12|OwnerIndex=1542|IsNotAccesible=T|IndexInSheet=5|OwnerPartId=1|OwnerPartDisplayMode=1|Location.X=260|Location.Y=770|Radius=16|LineWidth=1|StartAngle=270.000|EndAngle=299.000|Color=16711680
|RECORD=2|OwnerIndex=1542|OwnerPartId=1|FormalType=1|Electrical=4|PinConglomerate=35|PinLength=10|Location.X=260|Location.Y=750|Name=1|Designator=1|PinPropagationDelay=0.000000E+000
|RECORD=2|OwnerIndex=1542|OwnerPartId=1|FormalType=1|Electrical=4|PinConglomerate=33|PinLength=10|Location.X=260|Location.Y=760|Name=2|Designator=2|PinPropagationDelay=0.000000E+000
|RECORD=13|OwnerIndex=1542|IsNotAccesible=T|IndexInSheet=8|OwnerPartId=1|Location.X=252|Location.Y=757|Corner.X=268|Corner.Y=757|LineWidth=1|Color=16711680
|RECORD=13|OwnerIndex=1542|IsNotAccesible=T|IndexInSheet=9|OwnerPartId=1|Location.X=268|Location.Y=753|Corner.X=252|Corner.Y=753|LineWidth=1|Color=16711680
|RECORD=6|OwnerIndex=1542|IsNotAccesible=T|IndexInSheet=10|OwnerPartId=1|LineWidth=1|Color=16711680|LocationCount=2|X1=260|Y1=750|X2=260|Y2=753
|RECORD=6|OwnerIndex=1542|IsNotAccesible=T|IndexInSheet=11|OwnerPartId=1|LineWidth=1|Color=16711680|LocationCount=2|X1=260|Y1=760|X2=260|Y2=757
|RECORD=41|OwnerIndex=1542|IndexInSheet=12|OwnerPartId=-1|Location.X=251|Location.Y=772|Color=8388608|FontID=1|IsHidden=T|Text=GRM1555C1H470JA01D|Name=Part Number
|RECORD=41|OwnerIndex=1542|IndexInSheet=13|OwnerPartId=-1|Location.X=251|Location.Y=772|Color=8388608|FontID=1|IsHidden=T|Text=Murata|Name=Manufacturer
|RECORD=34|OwnerIndex=1542|IndexInSheet=-1|OwnerPartId=-1|Location.X=250|Location.Y=740|Orientation=1|Color=8388608|FontID=2|Text=C87|Name=Designator|ReadOnlyState=1
|RECORD=41|OwnerIndex=1542|IndexInSheet=-1|OwnerPartId=-1|Location.X=280|Location.Y=720|Orientation=1|Color=8388608|FontID=2|Text=47pF_50V_0402|Name=Comment
|RECORD=44|OwnerIndex=1542
|RECORD=45|OwnerIndex=1563|IndexInSheet=-1|Description=Chip Capacitor, 2-Leads, Body 1.00x0.50mm, IPC High Density|UseComponentLibrary=T|ModelName=CAPC1005X55X25LL05T10|ModelType=PCBLIB|DatafileCount=1|ModelDatafileEntity0=CAPC1005X55X25LL05T10|ModelDatafileKind0=PCBLib|IsCurrent=T|DatalinksLocked=T|DatabaseDatalinksLocked=T
|RECORD=46|OwnerIndex=1564
|RECORD=48|OwnerIndex=1564
|RECORD=41|OwnerIndex=1566|IndexInSheet=-1|OwnerPartId=-1|Color=8388608|FontID=1|IsHidden=T|Text=2D|Name=Available Preview Images
|RECORD=45|OwnerIndex=1563|IndexInSheet=-1|Description=Chip Capacitor, 2-Leads, Body 1.00x0.50mm, IPC Medium Density|UseComponentLibrary=T|ModelName=CAPC1005X55X25NL05T10|ModelType=PCBLIB|DatafileCount=1|ModelDatafileEntity0=CAPC1005X55X25NL05T10|ModelDatafileKind0=PCBLib|DatalinksLocked=T|DatabaseDatalinksLocked=T
|RECORD=46|OwnerIndex=1568
|RECORD=48|OwnerIndex=1568
|RECORD=41|OwnerIndex=1570|IndexInSheet=-1|OwnerPartId=-1|Color=8388608|FontID=1|IsHidden=T|Text=2D|Name=Available Preview Images
|RECORD=45|OwnerIndex=1563|IndexInSheet=-1|Description=Chip Capacitor, 2-Leads, Body 1.00x0.50mm, IPC Low Density|UseComponentLibrary=T|ModelName=CAPC1005X55X25ML05T10|ModelType=PCBLIB|DatafileCount=1|ModelDatafileEntity0=CAPC1005X55X25ML05T10|ModelDatafileKind0=PCBLib|DatalinksLocked=T|DatabaseDatalinksLocked=T
|RECORD=46|OwnerIndex=1572
|RECORD=48|OwnerIndex=1572
|RECORD=41|OwnerIndex=1574|IndexInSheet=-1|OwnerPartId=-1|Color=8388608|FontID=1|IsHidden=T|Text=2D|Name=Available Preview Images
|RECORD=1|LibReference=CAP|PartCount=2|DisplayModeCount=2|IndexInSheet=135|OwnerPartId=-1|Location.X=290|Location.Y=750|Orientation=1|CurrentPartId=1|SourceLibraryName=Altium Content Vault|TargetFileName=*|AreaColor=11599871|Color=128|PartIDLocked=F|DesignItemId=CMP-2008-04368-1|AllPinCount=2
|RECORD=2|OwnerIndex=1576|OwnerPartId=1|OwnerPartDisplayMode=1|FormalType=1|Electrical=4|PinConglomerate=35|PinLength=10|Location.X=300|Location.Y=750|Name=1|Designator=1|PinPropagationDelay=0.000000E+000
|RECORD=2|OwnerIndex=1576|OwnerPartId=1|OwnerPartDisplayMode=1|FormalType=1|Electrical=4|PinConglomerate=33|PinLength=10|Location.X=300|Location.Y=760|Name=2|Designator=2|PinPropagationDelay=0.000000E+000
|RECORD=13|OwnerIndex=1576|IsNotAccesible=T|IndexInSheet=2|OwnerPartId=1|OwnerPartDisplayMode=1|Location.X=308|Location.Y=750|Corner.X=292|Corner.Y=750|LineWidth=1|Color=16711680
|RECORD=13|OwnerIndex=1576|IsNotAccesible=T|IndexInSheet=3|OwnerPartId=1|OwnerPartDisplayMode=1|Location.X=300|Location.Y=754|Corner.X=300|Corner.Y=760|LineWidth=1|Color=16711680
|RECORD=12|OwnerIndex=1576|IsNotAccesible=T|IndexInSheet=4|OwnerPartId=1|OwnerPartDisplayMode=1|Location.X=300|Location.Y=770|Radius=16|LineWidth=1|StartAngle=241.000|EndAngle=270.000|Color=16711680
|RECORD=12|OwnerIndex=1576|IsNotAccesible=T|IndexInSheet=5|OwnerPartId=1|OwnerPartDisplayMode=1|Location.X=300|Location.Y=770|Radius=16|LineWidth=1|StartAngle=270.000|EndAngle=299.000|Color=16711680
|RECORD=2|OwnerIndex=1576|OwnerPartId=1|FormalType=1|Electrical=4|PinConglomerate=35|PinLength=10|Location.X=300|Location.Y=750|Name=1|Designator=1|PinPropagationDelay=0.000000E+000
|RECORD=2|OwnerIndex=1576|OwnerPartId=1|FormalType=1|Electrical=4|PinConglomerate=33|PinLength=10|Location.X=300|Location.Y=760|Name=2|Designator=2|PinPropagationDelay=0.000000E+000
|RECORD=13|OwnerIndex=1576|IsNotAccesible=T|IndexInSheet=8|OwnerPartId=1|Location.X=292|Location.Y=757|Corner.X=308|Corner.Y=757|LineWidth=1|Color=16711680
|RECORD=13|OwnerIndex=1576|IsNotAccesible=T|IndexInSheet=9|OwnerPartId=1|Location.X=308|Location.Y=753|Corner.X=292|Corner.Y=753|LineWidth=1|Color=16711680
|RECORD=6|OwnerIndex=1576|IsNotAccesible=T|IndexInSheet=10|OwnerPartId=1|LineWidth=1|Color=16711680|LocationCount=2|X1=300|Y1=750|X2=300|Y2=753
|RECORD=6|OwnerIndex=1576|IsNotAccesible=T|IndexInSheet=11|OwnerPartId=1|LineWidth=1|Color=16711680|LocationCount=2|X1=300|Y1=760|X2=300|Y2=757
|RECORD=41|OwnerIndex=1576|IndexInSheet=12|OwnerPartId=-1|Location.X=291|Location.Y=772|Color=8388608|FontID=1|IsHidden=T|Text=GRM1555C1H470JA01D|Name=Part Number
|RECORD=41|OwnerIndex=1576|IndexInSheet=13|OwnerPartId=-1|Location.X=291|Location.Y=772|Color=8388608|FontID=1|IsHidden=T|Text=Murata|Name=Manufacturer
|RECORD=34|OwnerIndex=1576|IndexInSheet=-1|OwnerPartId=-1|Location.X=290|Location.Y=740|Orientation=1|Color=8388608|FontID=2|Text=C88|Name=Designator|ReadOnlyState=1
|RECORD=41|OwnerIndex=1576|IndexInSheet=-1|OwnerPartId=-1|Location.X=320|Location.Y=720|Orientation=1|Color=8388608|FontID=2|Text=47pF_50V_0402|Name=Comment
|RECORD=44|OwnerIndex=1576
|RECORD=45|OwnerIndex=1597|IndexInSheet=-1|Description=Chip Capacitor, 2-Leads, Body 1.00x0.50mm, IPC High Density|UseComponentLibrary=T|ModelName=CAPC1005X55X25LL05T10|ModelType=PCBLIB|DatafileCount=1|ModelDatafileEntity0=CAPC1005X55X25LL05T10|ModelDatafileKind0=PCBLib|IsCurrent=T|DatalinksLocked=T|DatabaseDatalinksLocked=T
|RECORD=46|OwnerIndex=1598
|RECORD=48|OwnerIndex=1598
|RECORD=41|OwnerIndex=1600|IndexInSheet=-1|OwnerPartId=-1|Color=8388608|FontID=1|IsHidden=T|Text=2D|Name=Available Preview Images
|RECORD=45|OwnerIndex=1597|IndexInSheet=-1|Description=Chip Capacitor, 2-Leads, Body 1.00x0.50mm, IPC Medium Density|UseComponentLibrary=T|ModelName=CAPC1005X55X25NL05T10|ModelType=PCBLIB|DatafileCount=1|ModelDatafileEntity0=CAPC1005X55X25NL05T10|ModelDatafileKind0=PCBLib|DatalinksLocked=T|DatabaseDatalinksLocked=T
|RECORD=46|OwnerIndex=1602
|RECORD=48|OwnerIndex=1602
|RECORD=41|OwnerIndex=1604|IndexInSheet=-1|OwnerPartId=-1|Color=8388608|FontID=1|IsHidden=T|Text=2D|Name=Available Preview Images
|RECORD=45|OwnerIndex=1597|IndexInSheet=-1|Description=Chip Capacitor, 2-Leads, Body 1.00x0.50mm, IPC Low Density|UseComponentLibrary=T|ModelName=CAPC1005X55X25ML05T10|ModelType=PCBLIB|DatafileCount=1|ModelDatafileEntity0=CAPC1005X55X25ML05T10|ModelDatafileKind0=PCBLib|DatalinksLocked=T|DatabaseDatalinksLocked=T
|RECORD=46|OwnerIndex=1606
|RECORD=48|OwnerIndex=1606
|RECORD=41|OwnerIndex=1608|IndexInSheet=-1|OwnerPartId=-1|Color=8388608|FontID=1|IsHidden=T|Text=2D|Name=Available Preview Images
|RECORD=1|LibReference=USB-5-6SHLD|ComponentDescription=Right Angle Female Type AB Micro USB Connector, 30 V, 1.8 A, -30 to 85 degC, RoHS, Tape and Reel|PartCount=2|DisplayModeCount=1|IndexInSheet=136|OwnerPartId=-1|Location.X=100|Location.Y=840|IsMirrored=T|CurrentPartId=1|LibraryPath=*|SourceLibraryName=Altium Content Vault|TargetFileName=*|AreaColor=11599871|Color=128|PartIDLocked=T|DesignItemId=CMP-2000-05610-1|AllPinCount=11
|RECORD=2|OwnerIndex=1610|OwnerPartId=1|FormalType=1|Electrical=4|PinConglomerate=56|PinLength=20|Location.X=100|Location.Y=830|Name=VBUS|Designator=1|PinPropagationDelay=0.000000E+000
|RECORD=2|OwnerIndex=1610|OwnerPartId=1|FormalType=1|Electrical=4|PinConglomerate=56|PinLength=20|Location.X=100|Location.Y=820|Name=D-|Designator=2|PinPropagationDelay=0.000000E+000
|RECORD=2|OwnerIndex=1610|OwnerPartId=1|FormalType=1|Electrical=4|PinConglomerate=56|PinLength=20|Location.X=100|Location.Y=810|Name=D+|Designator=3|PinPropagationDelay=0.000000E+000
|RECORD=2|OwnerIndex=1610|OwnerPartId=1|FormalType=1|Electrical=4|PinConglomerate=56|PinLength=20|Location.X=100|Location.Y=800|Name=ID|Designator=4|PinPropagationDelay=0.000000E+000
|RECORD=2|OwnerIndex=1610|OwnerPartId=1|FormalType=1|Electrical=4|PinConglomerate=56|PinLength=20|Location.X=100|Location.Y=790|Name=GND|Designator=5|PinPropagationDelay=0.000000E+000
|RECORD=13|OwnerIndex=1610|IsNotAccesible=T|IndexInSheet=5|OwnerPartId=1|Location.X=50|Location.Y=730|Corner.X=50|Corner.Y=830|LineWidth=1|Color=16711680
|RECORD=13|OwnerIndex=1610|IsNotAccesible=T|IndexInSheet=6|OwnerPartId=1|Location.X=60|Location.Y=840|Corner.X=100|Corner.Y=840|LineWidth=1|Color=16711680
|RECORD=13|OwnerIndex=1610|IsNotAccesible=T|IndexInSheet=7|OwnerPartId=1|Location.X=60|Location.Y=840|Corner.X=50|Corner.Y=830|LineWidth=1|Color=16711680
|RECORD=13|OwnerIndex=1610|IsNotAccesible=T|IndexInSheet=8|OwnerPartId=1|Location.X=50|Location.Y=730|Corner.X=60|Corner.Y=720|LineWidth=1|Color=16711680
|RECORD=2|OwnerIndex=1610|OwnerPartId=1|FormalType=1|Electrical=4|PinConglomerate=56|PinLength=20|Location.X=100|Location.Y=780|Name=SHLD1|Designator=6|PinPropagationDelay=0.000000E+000
|RECORD=2|OwnerIndex=1610|OwnerPartId=1|FormalType=1|Electrical=4|PinConglomerate=56|PinLength=20|Location.X=100|Location.Y=770|Name=SHLD2|Designator=7|PinPropagationDelay=0.000000E+000
|RECORD=2|OwnerIndex=1610|OwnerPartId=1|FormalType=1|Electrical=4|PinConglomerate=56|PinLength=20|Location.X=100|Location.Y=760|Name=SHLD3|Designator=8|PinPropagationDelay=0.000000E+000
|RECORD=2|OwnerIndex=1610|OwnerPartId=1|FormalType=1|Electrical=4|PinConglomerate=56|PinLength=20|Location.X=100|Location.Y=750|Name=SHLD4|Designator=9|PinPropagationDelay=0.000000E+000
|RECORD=13|OwnerIndex=1610|IsNotAccesible=T|IndexInSheet=13|OwnerPartId=1|Location.X=63|Location.X_Frac=70000|Location.Y=803|Location.Y_Frac=66142|Corner.X=63|Corner.X_Frac=70000|Corner.Y=795|Corner.Y_Frac=19685|LineWidth=1|Color=16711680
|RECORD=13|OwnerIndex=1610|IsNotAccesible=T|IndexInSheet=14|OwnerPartId=1|Location.X=63|Location.X_Frac=70000|Location.Y=806|Location.Y_Frac=61417|Corner.X=63|Corner.X_Frac=70000|Corner.Y=803|Corner.Y_Frac=66142|LineWidth=1|Color=16711680
|RECORD=13|OwnerIndex=1610|IsNotAccesible=T|IndexInSheet=15|OwnerPartId=1|Location.X=57|Location.X_Frac=40000|Location.Y=807|Location.Y_Frac=79528|Corner.X=57|Corner.X_Frac=40000|Corner.Y=811|Corner.Y_Frac=73228|LineWidth=1|Color=16711680
|RECORD=13|OwnerIndex=1610|IsNotAccesible=T|IndexInSheet=16|OwnerPartId=1|Location.X=69|Location.X_Frac=40000|Location.Y=809|Location.Y_Frac=96063|Corner.X=69|Corner.X_Frac=40000|Corner.Y=814|Corner.Y_Frac=68504|LineWidth=1|Color=16711680
|RECORD=13|OwnerIndex=1610|IsNotAccesible=T|IndexInSheet=17|OwnerPartId=1|Location.X=63|Location.X_Frac=70000|Location.Y=806|Location.Y_Frac=61417|Corner.X=69|Corner.X_Frac=40000|Corner.Y=809|Corner.Y_Frac=96063|LineWidth=1|Color=16711680
|RECORD=13|OwnerIndex=1610|IsNotAccesible=T|IndexInSheet=18|OwnerPartId=1|Location.X=63|Location.X_Frac=70000|Location.Y=803|Location.Y_Frac=66142|Corner.X=57|Corner.X_Frac=40000|Corner.Y=807|Corner.Y_Frac=79528|LineWidth=1|Color=16711680
|RECORD=13|OwnerIndex=1610|IsNotAccesible=T|IndexInSheet=19|OwnerPartId=1|Location.X=63|Location.X_Frac=70000|Location.Y=821|Location.Y_Frac=18110|Corner.X=63|Corner.X_Frac=70000|Corner.Y=806|Corner.Y_Frac=61417|LineWidth=1|Color=16711680
|RECORD=13|OwnerIndex=1610|IsNotAccesible=T|IndexInSheet=20|OwnerPartId=1|Location.X=66|Location.X_Frac=80000|Location.Y=821|Location.Y_Frac=18110|Corner.X=63|Corner.X_Frac=70000|Corner.Y=821|Corner.Y_Frac=18110|LineWidth=1|Color=16711680
|RECORD=13|OwnerIndex=1610|IsNotAccesible=T|IndexInSheet=21|OwnerPartId=1|Location.X=66|Location.X_Frac=80000|Location.Y=821|Location.Y_Frac=96850|Corner.X=66|Corner.X_Frac=80000|Corner.Y=821|Corner.Y_Frac=18110|LineWidth=1|Color=16711680
|RECORD=13|OwnerIndex=1610|IsNotAccesible=T|IndexInSheet=22|OwnerPartId=1|Location.X=63|Location.X_Frac=70000|Location.Y=825|Location.Y_Frac=11811|Corner.X=66|Corner.X_Frac=80000|Corner.Y=821|Corner.Y_Frac=96850|LineWidth=1|Color=16711680
|RECORD=13|OwnerIndex=1610|IsNotAccesible=T|IndexInSheet=23|OwnerPartId=1|Location.X=60|Location.X_Frac=50000|Location.Y=821|Location.Y_Frac=96850|Corner.X=63|Corner.X_Frac=70000|Corner.Y=825|Corner.Y_Frac=11811|LineWidth=1|Color=16711680
|RECORD=13|OwnerIndex=1610|IsNotAccesible=T|IndexInSheet=24|OwnerPartId=1|Location.X=60|Location.X_Frac=50000|Location.Y=821|Location.Y_Frac=96850|Corner.X=66|Corner.Y=821|Corner.Y_Frac=96850|LineWidth=1|Color=16711680
|RECORD=13|OwnerIndex=1610|IsNotAccesible=T|IndexInSheet=25|OwnerPartId=1|Location.X=60|Location.X_Frac=50000|Location.Y=821|Location.Y_Frac=18110|Corner.X=60|Corner.X_Frac=50000|Corner.Y=821|Corner.Y_Frac=96850|LineWidth=1|Color=16711680
|RECORD=13|OwnerIndex=1610|IsNotAccesible=T|IndexInSheet=26|OwnerPartId=1|Location.X=63|Location.X_Frac=70000|Location.Y=821|Location.Y_Frac=18110|Corner.X=60|Corner.X_Frac=50000|Corner.Y=821|Corner.Y_Frac=18110|LineWidth=1|Color=16711680
|RECORD=13|OwnerIndex=1610|IsNotAccesible=T|IndexInSheet=27|OwnerPartId=1|Location.X=64|Location.X_Frac=40000|Location.Y=823|Location.Y_Frac=54331|Corner.X=63|Corner.X_Frac=70000|Corner.Y=823|Corner.Y_Frac=54331|LineWidth=1|Color=16711680
|RECORD=13|OwnerIndex=1610|IsNotAccesible=T|IndexInSheet=28|OwnerPartId=1|Location.X=65|Location.X_Frac=20000|Location.Y=822|Location.Y_Frac=75591|Corner.X=64|Corner.X_Frac=40000|Corner.Y=823|Corner.Y_Frac=54331|LineWidth=1|Color=16711680
|RECORD=13|OwnerIndex=1610|IsNotAccesible=T|IndexInSheet=29|OwnerPartId=1|Location.X=62|Location.X_Frac=10000|Location.Y=822|Location.Y_Frac=75591|Corner.X=65|Corner.X_Frac=20000|Corner.Y=822|Corner.Y_Frac=75591|LineWidth=1|Color=16711680
|RECORD=13|OwnerIndex=1610|IsNotAccesible=T|IndexInSheet=30|OwnerPartId=1|Location.X=63|Location.X_Frac=70000|Location.Y=824|Location.Y_Frac=33071|Corner.X=62|Corner.X_Frac=10000|Corner.Y=822|Corner.Y_Frac=75591|LineWidth=1|Color=16711680
|RECORD=14|OwnerIndex=1610|IsNotAccesible=T|IndexInSheet=31|OwnerPartId=1|Location.X=67|Location.Y=813|Location.Y_Frac=30709|Corner.X=71|Corner.X_Frac=77165|Corner.Y=818|Corner.Y_Frac=3150|LineWidth=1|Color=16711680|AreaColor=16711680|IsSolid=T
|RECORD=12|OwnerIndex=1610|IsNotAccesible=T|IndexInSheet=32|OwnerPartId=1|Location.X=63|Location.X_Frac=70000|Location.Y=795|Location.Y_Frac=19685|Radius=2|LineWidth=3|EndAngle=360.000|Color=16711680
|RECORD=12|OwnerIndex=1610|IsNotAccesible=T|IndexInSheet=33|OwnerPartId=1|Location.X=57|Location.X_Frac=40000|Location.Y=813|Location.Y_Frac=30709|Radius_Frac=80000|LineWidth=3|EndAngle=360.000|Color=16711680
|RECORD=2|OwnerIndex=1610|OwnerPartId=1|FormalType=1|Electrical=4|PinConglomerate=56|PinLength=20|Location.X=100|Location.Y=730|Name=SHLD6|Designator=11|PinPropagationDelay=0.000000E+000
|RECORD=2|OwnerIndex=1610|OwnerPartId=1|FormalType=1|Electrical=4|PinConglomerate=56|PinLength=20|Location.X=100|Location.Y=740|Name=SHLD5|Designator=10|PinPropagationDelay=0.000000E+000
|RECORD=13|OwnerIndex=1610|IsNotAccesible=T|IndexInSheet=36|OwnerPartId=1|Location.X=100|Location.Y=720|Corner.X=60|Corner.Y=720|LineWidth=1|Color=16711680
|RECORD=6|OwnerIndex=1610|IsNotAccesible=T|IndexInSheet=37|OwnerPartId=1|LineWidth=1|Color=16711680|LocationCount=2|X1=100|Y1=840|X2=100|Y2=720
|RECORD=41|OwnerIndex=1610|IndexInSheet=38|OwnerPartId=-1|Location.X=49|Location.Y=841|Color=8388608|FontID=1|IsHidden=T|Text=1Port|Name=Number of Ports|IsMirrored=T
|RECORD=41|OwnerIndex=1610|IndexInSheet=39|OwnerPartId=-1|Location.X=49|Location.Y=841|Color=8388608|FontID=1|IsHidden=T|Text=Black|Name=Color|IsMirrored=T
|RECORD=41|OwnerIndex=1610|IndexInSheet=40|OwnerPartId=-1|Location.X=49|Location.Y=841|Color=8388608|FontID=1|IsHidden=T|Text=MicroUSBTypeABConnectors|Name=Product|IsMirrored=T
|RECORD=41|OwnerIndex=1610|IndexInSheet=41|OwnerPartId=-1|Location.X=49|Location.Y=841|Color=8388608|FontID=3|IsHidden=T|Text=http://www.molex.com/pdm_docs/sd/475890001_sd.pdf|Name=Package URL|IsMirrored=T
|RECORD=41|OwnerIndex=1610|IndexInSheet=42|OwnerPartId=-1|Location.X=49|Location.Y=841|Color=8388608|FontID=1|IsHidden=T|Text=Gold|Name=Contact Plating|IsMirrored=T
|RECORD=41|OwnerIndex=1610|IndexInSheet=43|OwnerPartId=-1|Location.X=49|Location.Y=841|Color=8388608|FontID=3|IsHidden=T|Text=http://www.molex.com/webdocs/datasheets/pdf/en-us/0475890001_IO_CONNECTORS.pdf|Name=Datasheet URL|IsMirrored=T
|RECORD=41|OwnerIndex=1610|IndexInSheet=44|OwnerPartId=-1|Location.X=49|Location.Y=841|Color=8388608|FontID=1|IsHidden=T|Text=-20Cto+85C|Name=Operating Temperature Range|IsMirrored=T
|RECORD=41|OwnerIndex=1610|IndexInSheet=45|OwnerPartId=-1|Location.X=49|Location.Y=841|Color=8388608|FontID=1|IsHidden=T|Text=SMD/SMT|Name=Termination Style|IsMirrored=T
|RECORD=41|OwnerIndex=1610|IndexInSheet=46|OwnerPartId=-1|Location.X=49|Location.Y=841|Color=8388608|FontID=1|IsHidden=T|Text=1.8A|Name=Current Rating|IsMirrored=T
|RECORD=41|OwnerIndex=1610|IndexInSheet=47|OwnerPartId=-1|Location.X=49|Location.Y=841|Color=8388608|FontID=1|IsHidden=T|Text=0475890001|IsMirrored=T
|RECORD=41|OwnerIndex=1610|IndexInSheet=48|OwnerPartId=-1|Location.X=49|Location.Y=841|Color=8388608|FontID=1|IsHidden=T|Text=Molex|Name=Brand|IsMirrored=T
|RECORD=41|OwnerIndex=1610|IndexInSheet=49|OwnerPartId=-1|Location.X=49|Location.Y=841|Color=8388608|FontID=1|IsHidden=T|Text=Right|Name=Mounting Angle|IsMirrored=T
|RECORD=41|OwnerIndex=1610|IndexInSheet=50|OwnerPartId=-1|Location.X=49|Location.Y=841|Color=8388608|FontID=1|IsHidden=T|Text=47589-0001|Name=Package Reference|IsMirrored=T
|RECORD=41|OwnerIndex=1610|IndexInSheet=51|OwnerPartId=-1|Location.X=49|Location.Y=841|Color=8388608|FontID=1|IsHidden=T|Text=Female|Name=Gender|IsMirrored=T
|RECORD=41|OwnerIndex=1610|IndexInSheet=52|OwnerPartId=-1|Location.X=49|Location.Y=841|Color=8388608|FontID=1|IsHidden=T|Text=Micro USB Connector, Pitch 0.65 mm, 5 Positions, Body 7.5 x 5.6 mm|Name=Package Description|IsMirrored=T
|RECORD=41|OwnerIndex=1610|IndexInSheet=53|OwnerPartId=-1|Location.X=49|Location.Y=841|Color=8388608|FontID=1|IsHidden=T|Text=SurfaceMount|Name=Mounting Technology|IsMirrored=T
|RECORD=41|OwnerIndex=1610|IndexInSheet=54|OwnerPartId=-1|Location.X=49|Location.Y=841|Color=8388608|FontID=1|IsHidden=T|Text=CopperAlloy|Name=Contact Material|IsMirrored=T
|RECORD=41|OwnerIndex=1610|IndexInSheet=55|OwnerPartId=-1|Location.X=49|Location.Y=841|Color=8388608|FontID=1|IsHidden=T|Text=MicroUSBTypeABreceptacle|Name=Connector Type|IsMirrored=T
|RECORD=41|OwnerIndex=1610|IndexInSheet=56|OwnerPartId=-1|Location.X=49|Location.Y=841|Color=8388608|FontID=1|IsHidden=T|Text=Reel|Name=Packaging|IsMirrored=T
|RECORD=41|OwnerIndex=1610|IndexInSheet=57|OwnerPartId=-1|Location.X=49|Location.Y=841|Color=8388608|FontID=1|IsHidden=T|Text=True|Name=RoHS|IsMirrored=T
|RECORD=41|OwnerIndex=1610|IndexInSheet=58|OwnerPartId=-1|Location.X=49|Location.Y=841|Color=8388608|FontID=1|IsHidden=T|Text=USB|Name=Standard|IsMirrored=T
|RECORD=41|OwnerIndex=1610|IndexInSheet=59|OwnerPartId=-1|Location.X=49|Location.Y=841|Color=8388608|FontID=3|IsHidden=T|Text=http://www.molex.com/|Name=Manufacturer URL|IsMirrored=T
|RECORD=41|OwnerIndex=1610|IndexInSheet=60|OwnerPartId=-1|Location.X=49|Location.Y=841|Color=8388608|FontID=1|IsHidden=T|Text=Molex|Name=Manufacturer|IsMirrored=T
|RECORD=41|OwnerIndex=1610|IndexInSheet=61|OwnerPartId=-1|Location.X=49|Location.Y=841|Color=8388608|FontID=1|IsHidden=T|Text=12/2016|Name=Datasheet Version|IsMirrored=T
|RECORD=41|OwnerIndex=1610|IndexInSheet=62|OwnerPartId=-1|Location.X=49|Location.Y=841|Color=8388608|FontID=1|IsHidden=T|Text=5Contact|Name=Number of Contacts|IsMirrored=T
|RECORD=41|OwnerIndex=1610|IndexInSheet=63|OwnerPartId=-1|Location.X=49|Location.Y=841|Color=8388608|FontID=1|IsHidden=T|Text=USBConnectors|Name=Product Category|IsMirrored=T
|RECORD=41|OwnerIndex=1610|IndexInSheet=64|OwnerPartId=-1|Location.X=49|Location.Y=841|Color=8388608|FontID=1|IsHidden=T|Text=47589|Name=Series|IsMirrored=T
|RECORD=41|OwnerIndex=1610|IndexInSheet=65|OwnerPartId=-1|Location.X=49|Location.Y=841|Color=8388608|FontID=1|IsHidden=T|Text=30VAC|Name=Voltage Rating|IsMirrored=T
|RECORD=34|OwnerIndex=1610|IndexInSheet=-1|OwnerPartId=-1|Location.X=49|Location.Y=841|Color=8388608|FontID=1|Text=J43|Name=Designator|ReadOnlyState=1|IsMirrored=T
|RECORD=41|OwnerIndex=1610|IndexInSheet=-1|OwnerPartId=-1|Location.X=49|Location.Y=709|Color=8388608|FontID=1|Text=47589-0001|Name=Comment|IsMirrored=T
|RECORD=44|OwnerIndex=1610
|RECORD=45|OwnerIndex=1690|IndexInSheet=-1|Description=SMD, 5-Leads, Body 7.5x5.6mm, Pitch 0.65mm|UseComponentLibrary=T|ModelName=MOLX-47589-0001_V|ModelType=PCBLIB|DatafileCount=1|ModelDatafileEntity0=MOLX-47589-0001_V|ModelDatafileKind0=PCBLib|IsCurrent=T|DatalinksLocked=T|DatabaseDatalinksLocked=T
|RECORD=46|OwnerIndex=1691
|RECORD=48|OwnerIndex=1691
|RECORD=41|OwnerIndex=1693|IndexInSheet=-1|OwnerPartId=-1|Color=8388608|FontID=1|IsHidden=T|Text=2D|Name=Available Preview Images
|RECORD=1|LibReference=a38d0f79c2a9f01c07a7e52882ed186|ComponentDescription=IC REG LINEAR 3.3V 500MA 6XDFN|PartCount=2|DisplayModeCount=1|IndexInSheet=137|OwnerPartId=-1|Location.X=190|Location.Y=550|CurrentPartId=1|LibraryPath=*|SourceLibraryName=Altium Content Vault|TargetFileName=*|AreaColor=11599871|Color=128|PartIDLocked=T|DesignItemId=CMP-07128-000022-1|AllPinCount=7
|RECORD=14|OwnerIndex=1695|IsNotAccesible=T|OwnerPartId=1|Location.X=210|Location.Y=470|Corner.X=280|Corner.Y=560|LineWidth=1|Color=128|AreaColor=11599871|IsSolid=T
|RECORD=2|OwnerIndex=1695|OwnerPartId=1|PinConglomerate=58|PinLength=20|Location.X=210|Location.Y=530|Name=EN|Designator=4|PinPropagationDelay=0.000000E+000
|RECORD=2|OwnerIndex=1695|OwnerPartId=1|PinConglomerate=56|PinLength=20|Location.X=280|Location.Y=530|Name=FB|Designator=2|PinPropagationDelay=0.000000E+000
|RECORD=2|OwnerIndex=1695|OwnerPartId=1|Electrical=7|PinConglomerate=58|PinLength=20|Location.X=210|Location.Y=550|Name=IN|Designator=6|PinPropagationDelay=0.000000E+000
|RECORD=2|OwnerIndex=1695|OwnerPartId=1|Electrical=4|PinConglomerate=56|PinLength=20|Location.X=280|Location.Y=510|Name=NC|Designator=5|PinPropagationDelay=0.000000E+000
|RECORD=2|OwnerIndex=1695|OwnerPartId=1|Electrical=2|PinConglomerate=56|PinLength=20|Location.X=280|Location.Y=550|Name=OUT|Designator=1|PinPropagationDelay=0.000000E+000
|RECORD=2|OwnerIndex=1695|OwnerPartId=1|Electrical=7|PinConglomerate=56|PinLength=20|Location.X=280|Location.Y=490|Name=GND|Designator=3|PinPropagationDelay=0.000000E+000
|RECORD=2|OwnerIndex=1695|OwnerPartId=1|Electrical=7|PinConglomerate=56|PinLength=20|Location.X=280|Location.Y=480|Name=GND|Designator=7|PinPropagationDelay=0.000000E+000
|RECORD=41|OwnerIndex=1695|IndexInSheet=8|OwnerPartId=-1|Location.X=188|Location.Y=560|Color=8388608|FontID=3|IsHidden=T|Text=https://www.onsemi.com/pub/Collateral/711AT.PDF|Name=Footprint Url
|RECORD=41|OwnerIndex=1695|IndexInSheet=9|OwnerPartId=-1|Location.X=188|Location.Y=560|Color=8388608|FontID=1|IsHidden=T|Text=Power Management ICs|Name=Device Class L2
|RECORD=41|OwnerIndex=1695|IndexInSheet=10|OwnerPartId=-1|Location.X=188|Location.Y=560|Color=8388608|FontID=1|IsHidden=T|Text=Integrated Circuits (ICs)|Name=Device Class L1
|RECORD=41|OwnerIndex=1695|IndexInSheet=11|OwnerPartId=-1|Location.X=188|Location.Y=560|Color=8388608|FontID=1|IsHidden=T|Text=IC REG LINEAR 3.3V 500MA 6XDFN|Name=Digikey Description
|RECORD=41|OwnerIndex=1695|IndexInSheet=12|OwnerPartId=-1|Location.X=188|Location.Y=560|Color=8388608|FontID=1|IsHidden=T|Text=Datasheet|Name=ComponentLink2Description
|RECORD=41|OwnerIndex=1695|IndexInSheet=13|OwnerPartId=-1|Location.X=188|Location.Y=560|Color=8388608|FontID=1|IsHidden=T|Text=3.3V|Name=Output Voltage
|RECORD=41|OwnerIndex=1695|IndexInSheet=14|OwnerPartId=-1|Location.X=188|Location.Y=560|Color=8388608|FontID=1|IsHidden=T|Text=Fixed|Name=Output Type
|RECORD=41|OwnerIndex=1695|IndexInSheet=15|OwnerPartId=-1|Location.X=188|Location.Y=560|Color=8388608|FontID=3|IsHidden=T|Text=https://www.onsemi.com/pub/Collateral/NCP176-D.PDF|Name=ComponentLink2URL
|RECORD=41|OwnerIndex=1695|IndexInSheet=16|OwnerPartId=-1|Location.X=188|Location.Y=560|Color=8388608|FontID=1|IsHidden=T|Text=TRUE|Name=RoHS
|RECORD=41|OwnerIndex=1695|IndexInSheet=17|OwnerPartId=-1|Location.X=188|Location.Y=560|Color=8388608|FontID=1|IsHidden=T|Text=295mV|Name=Dropout Voltage
|RECORD=41|OwnerIndex=1695|IndexInSheet=18|OwnerPartId=-1|Location.X=188|Location.Y=560|Color=8388608|FontID=1|IsHidden=T|Text=1|Name=Number Of Outputs
|RECORD=41|OwnerIndex=1695|IndexInSheet=19|OwnerPartId=-1|Location.X=188|Location.Y=560|Color=8388608|FontID=1|IsHidden=T|Text=ON Semiconductor|Name=Manufacturer
|RECORD=41|OwnerIndex=1695|IndexInSheet=20|OwnerPartId=-1|Location.X=188|Location.Y=560|Color=8388608|FontID=1|IsHidden=T|Text=Yes|Name=Lead Free
|RECORD=41|OwnerIndex=1695|IndexInSheet=21|OwnerPartId=-1|Location.X=188|Location.Y=560|Color=8388608|FontID=1|IsHidden=T|Text=500mA|Name=Output Current
|RECORD=41|OwnerIndex=1695|IndexInSheet=22|OwnerPartId=-1|Location.X=188|Location.Y=560|Color=8388608|FontID=1|IsHidden=T|Text=No|Name=Automotive
|RECORD=41|OwnerIndex=1695|IndexInSheet=23|OwnerPartId=-1|Location.X=188|Location.Y=560|Color=8388608|FontID=1|IsHidden=T|Text=+150°C|Name=Temperature Range High
|RECORD=41|OwnerIndex=1695|IndexInSheet=24|OwnerPartId=-1|Location.X=188|Location.Y=560|Color=8388608|FontID=1|IsHidden=T|Text=0.45mm|Name=Height
|RECORD=41|OwnerIndex=1695|IndexInSheet=25|OwnerPartId=-1|Location.X=188|Location.Y=560|Color=8388608|FontID=1|IsHidden=T|Text=0mm|Name=Standoff Height
|RECORD=41|OwnerIndex=1695|IndexInSheet=26|OwnerPartId=-1|Location.X=188|Location.Y=560|Color=8388608|FontID=1|IsHidden=T|Text=1.4V|Name=Min Supply Voltage
|RECORD=41|OwnerIndex=1695|IndexInSheet=27|OwnerPartId=-1|Location.X=188|Location.Y=560|Color=8388608|FontID=1|IsHidden=T|Text=60uA|Name=Nominal Supply Current
|RECORD=41|OwnerIndex=1695|IndexInSheet=28|OwnerPartId=-1|Location.X=188|Location.Y=560|Color=8388608|FontID=1|IsHidden=T|Text=5.5V|Name=Max Supply Voltage
|RECORD=41|OwnerIndex=1695|IndexInSheet=29|OwnerPartId=-1|Location.X=188|Location.Y=560|Color=8388608|FontID=1|IsHidden=T|Text=711AT|Name=Package
|RECORD=41|OwnerIndex=1695|IndexInSheet=30|OwnerPartId=-1|Location.X=188|Location.Y=560|Color=8388608|FontID=1|IsHidden=T|Text=Voltage Regulators - Linear|Name=Device Class L3
|RECORD=41|OwnerIndex=1695|IndexInSheet=31|OwnerPartId=-1|Location.X=188|Location.Y=560|Color=8388608|FontID=1|IsHidden=T|Text=+150°C|Name=Max Junction Temp
|RECORD=41|OwnerIndex=1695|IndexInSheet=32|OwnerPartId=-1|Location.X=188|Location.Y=560|Color=8388608|FontID=3|IsHidden=T|Text=https://octopart.com/ncp176amx330tcg-on+semiconductor-61522616|Name=Octopart
|RECORD=41|OwnerIndex=1695|IndexInSheet=33|OwnerPartId=-1|Location.X=188|Location.Y=560|Color=8388608|FontID=1|IsHidden=T|Text=IC|Name=Category
|RECORD=41|OwnerIndex=1695|IndexInSheet=34|OwnerPartId=-1|Location.X=188|Location.Y=560|Color=8388608|FontID=1|IsHidden=T|Text=0.8%|Name=Accuracy Percentage
|RECORD=41|OwnerIndex=1695|IndexInSheet=35|OwnerPartId=-1|Location.X=188|Location.Y=560|Color=8388608|FontID=1|IsHidden=T|Text=NCP176AMX330TCG|Name=Manufacturer Part Number
|RECORD=41|OwnerIndex=1695|IndexInSheet=36|OwnerPartId=-1|Location.X=188|Location.Y=560|Color=8388608|FontID=1|IsHidden=T|Text=DFN120X120X37-6|Name=Ipc Land Pattern Name
|RECORD=41|OwnerIndex=1695|IndexInSheet=37|OwnerPartId=-1|Location.X=188|Location.Y=560|Color=8388608|FontID=1|IsHidden=T|Text=to +150°C|Name=Temperature
|RECORD=34|OwnerIndex=1695|IndexInSheet=-1|OwnerPartId=-1|Location.X=210|Location.Y=560|Color=8388608|FontID=1|Text=U33|Name=Designator|ReadOnlyState=1
|RECORD=41|OwnerIndex=1695|IndexInSheet=-1|OwnerPartId=1|Location.X=210|Location.Y=460|Color=8388608|FontID=1|Text=NCP176AMX330TCG|Name=Comment
|RECORD=44|OwnerIndex=1695
|RECORD=45|OwnerIndex=1743|IndexInSheet=-1|UseComponentLibrary=T|ModelName=FP-711AT-MFG|ModelType=PCBLIB|DatafileCount=1|ModelDatafileEntity0=FP-711AT-MFG|ModelDatafileKind0=PCBLib|IsCurrent=T|DatalinksLocked=T|DatabaseDatalinksLocked=T
|RECORD=46|OwnerIndex=1744
|RECORD=48|OwnerIndex=1744
|RECORD=45|OwnerIndex=1743|IndexInSheet=-1|UseComponentLibrary=T|ModelName=FP-711AT-IPC_C|ModelType=PCBLIB|DatafileCount=1|ModelDatafileEntity0=FP-711AT-IPC_C|ModelDatafileKind0=PCBLib|DatalinksLocked=T|DatabaseDatalinksLocked=T
|RECORD=46|OwnerIndex=1747
|RECORD=48|OwnerIndex=1747
|RECORD=45|OwnerIndex=1743|IndexInSheet=-1|UseComponentLibrary=T|ModelName=FP-711AT-IPC_B|ModelType=PCBLIB|DatafileCount=1|ModelDatafileEntity0=FP-711AT-IPC_B|ModelDatafileKind0=PCBLib|DatalinksLocked=T|DatabaseDatalinksLocked=T
|RECORD=46|OwnerIndex=1750
|RECORD=48|OwnerIndex=1750
|RECORD=45|OwnerIndex=1743|IndexInSheet=-1|UseComponentLibrary=T|ModelName=FP-711AT-IPC_A|ModelType=PCBLIB|DatafileCount=1|ModelDatafileEntity0=FP-711AT-IPC_A|ModelDatafileKind0=PCBLib|DatalinksLocked=T|DatabaseDatalinksLocked=T
|RECORD=46|OwnerIndex=1753
|RECORD=48|OwnerIndex=1753
|RECORD=1|LibReference=b4654b650e69147ec39a6b967a45e02|ComponentDescription=General Purpose Ceramic Capacitor, 0402, 100nF, 10%, X7R, 15%, 25V|PartCount=2|DisplayModeCount=1|IndexInSheet=138|OwnerPartId=-1|Location.X=110|Location.Y=520|CurrentPartId=1|LibraryPath=*|SourceLibraryName=Altium Content Vault|TargetFileName=*|AreaColor=11599871|Color=128|PartIDLocked=T|DesignItemId=CMP-2008-02519-2|AllPinCount=2
|RECORD=2|OwnerIndex=1756|OwnerPartId=1|Electrical=4|PinConglomerate=49|PinLength=7|Location.X=110|Location.Y=513|Name=1|Designator=1|PinPropagationDelay=0.000000E+000
|RECORD=2|OwnerIndex=1756|OwnerPartId=1|Electrical=4|PinConglomerate=51|PinLength=6|Location.X=110|Location.Y=506|Name=2|Designator=2|PinPropagationDelay=0.000000E+000
|RECORD=13|OwnerIndex=1756|IsNotAccesible=T|IndexInSheet=2|OwnerPartId=1|Location.X=120|Location.Y=513|Corner.X=100|Corner.Y=513|LineWidth=1|Color=16711680
|RECORD=13|OwnerIndex=1756|IsNotAccesible=T|IndexInSheet=3|OwnerPartId=1|Location.X=120|Location.Y=507|Corner.X=100|Corner.Y=507|LineWidth=1|Color=16711680
|RECORD=13|OwnerIndex=1756|IsNotAccesible=T|IndexInSheet=4|OwnerPartId=1|Location.X=110|Location.Y=513|Corner.X=110|Corner.Y=516|LineWidth=1|Color=16711680
|RECORD=13|OwnerIndex=1756|IsNotAccesible=T|IndexInSheet=5|OwnerPartId=1|Location.X=110|Location.Y=506|Corner.X=110|Corner.Y=505|LineWidth=1|Color=16711680
|RECORD=41|OwnerIndex=1756|IndexInSheet=6|OwnerPartId=-1|Location.X=99|Location.Y=522|Color=8388608|FontID=1|IsHidden=T|Text=1|Name=Package Quantity
|RECORD=41|OwnerIndex=1756|IndexInSheet=7|OwnerPartId=-1|Location.X=99|Location.Y=522|Color=8388608|FontID=1|IsHidden=T|Text=100nF|Name=Capacitance
|RECORD=41|OwnerIndex=1756|IndexInSheet=8|OwnerPartId=-1|Location.X=99|Location.Y=522|Color=8388608|FontID=1|IsHidden=T|Text=-55°C|Name=Min Operating Temperature
|RECORD=41|OwnerIndex=1756|IndexInSheet=9|OwnerPartId=-1|Location.X=99|Location.Y=522|Color=8388608|FontID=1|IsHidden=T|Text=25V|Name=Voltage
|RECORD=41|OwnerIndex=1756|IndexInSheet=10|OwnerPartId=-1|Location.X=99|Location.Y=522|Color=8388608|FontID=1|IsHidden=T|Text=25V|Name=Voltage Rating
|RECORD=41|OwnerIndex=1756|IndexInSheet=11|OwnerPartId=-1|Location.X=99|Location.Y=522|Color=8388608|FontID=1|IsHidden=T|Text=Flat|Name=Construction
|RECORD=41|OwnerIndex=1756|IndexInSheet=12|OwnerPartId=-1|Location.X=99|Location.Y=522|Color=8388608|FontID=1|IsHidden=T|Text=125°C|Name=Max Operating Temperature
|RECORD=41|OwnerIndex=1756|IndexInSheet=13|OwnerPartId=-1|Location.X=99|Location.Y=522|Color=8388608|FontID=1|IsHidden=T|Text=No|Name=Radiation Hardening
|RECORD=41|OwnerIndex=1756|IndexInSheet=14|OwnerPartId=-1|Location.X=99|Location.Y=522|Color=8388608|FontID=1|IsHidden=T|Text=0.5mm|Name=Depth
|RECORD=41|OwnerIndex=1756|IndexInSheet=15|OwnerPartId=-1|Location.X=99|Location.Y=522|Color=8388608|FontID=1|IsHidden=T|Text=0.022inch|Name=Thickness
|RECORD=41|OwnerIndex=1756|IndexInSheet=16|OwnerPartId=-1|Location.X=99|Location.Y=522|Color=8388608|FontID=1|IsHidden=T|Text=25V|Name=Voltage Rating (DC)
|RECORD=41|OwnerIndex=1756|IndexInSheet=17|OwnerPartId=-1|Location.X=99|Location.Y=522|Color=8388608|FontID=1|IsHidden=T|Text=2|Name=Number of Pins
|RECORD=41|OwnerIndex=1756|IndexInSheet=18|OwnerPartId=-1|Location.X=99|Location.Y=522|Color=8388608|FontID=1|IsHidden=T|Text=Lead Free|Name=Lead Free
|RECORD=41|OwnerIndex=1756|IndexInSheet=19|OwnerPartId=-1|Location.X=99|Location.Y=522|Color=8388608|FontID=1|IsHidden=T|Text=-|Name=Series
|RECORD=41|OwnerIndex=1756|IndexInSheet=20|OwnerPartId=-1|Location.X=99|Location.Y=522|Color=8388608|FontID=1|IsHidden=T|Text=No SVHC|Name=REACH SVHC
|RECORD=41|OwnerIndex=1756|IndexInSheet=21|OwnerPartId=-1|Location.X=99|Location.Y=522|Color=8388608|FontID=1|IsHidden=T|Text=1mm|Name=Length
|RECORD=41|OwnerIndex=1756|IndexInSheet=22|OwnerPartId=-1|Location.X=99|Location.Y=522|Color=8388608|FontID=1|IsHidden=T|Text=X7R|Name=Dielectric
|RECORD=41|OwnerIndex=1756|IndexInSheet=23|OwnerPartId=-1|Location.X=99|Location.Y=522|Color=8388608|FontID=1|IsHidden=T|Text=Yes|Name=RoHS Compliant
|RECORD=41|OwnerIndex=1756|IndexInSheet=24|OwnerPartId=-1|Location.X=99|Location.Y=522|Color=8388608|FontID=1|IsHidden=T|Text=Surface Mount|Name=Mount
|RECORD=41|OwnerIndex=1756|IndexInSheet=25|OwnerPartId=-1|Location.X=99|Location.Y=522|Color=8388608|FontID=1|IsHidden=T|Text=Tape and Reel|Name=Packaging
|RECORD=41|OwnerIndex=1756|IndexInSheet=26|OwnerPartId=-1|Location.X=99|Location.Y=522|Color=8388608|FontID=1|IsHidden=T|Text=0402|Name=Case/Package
|RECORD=41|OwnerIndex=1756|IndexInSheet=27|OwnerPartId=-1|Location.X=99|Location.Y=522|Color=8388608|FontID=1|IsHidden=T|Text=0402|Name=Case Code (Imperial)
|RECORD=41|OwnerIndex=1756|IndexInSheet=28|OwnerPartId=-1|Location.X=99|Location.Y=522|Color=8388608|FontID=1|IsHidden=T|Text=SMD/SMT|Name=Termination
|RECORD=41|OwnerIndex=1756|IndexInSheet=29|OwnerPartId=-1|Location.X=99|Location.Y=522|Color=8388608|FontID=1|IsHidden=T|Text=0.02inch|Name=Width
|RECORD=41|OwnerIndex=1756|IndexInSheet=30|OwnerPartId=-1|Location.X=99|Location.Y=522|Color=8388608|FontID=1|IsHidden=T|Text=1005|Name=Case Code (Metric)
|RECORD=41|OwnerIndex=1756|IndexInSheet=31|OwnerPartId=-1|Location.X=99|Location.Y=522|Color=8388608|FontID=1|IsHidden=T|Text=10%|Name=Tolerance
|RECORD=34|OwnerIndex=1756|IndexInSheet=-1|OwnerPartId=-1|Location.X=100|Location.Y=500|Orientation=1|Color=8388608|FontID=2|Text=C115|Name=Designator|ReadOnlyState=1
|RECORD=41|OwnerIndex=1756|IndexInSheet=-1|OwnerPartId=1|Location.X=130|Location.Y=485|Orientation=1|Color=8388608|FontID=2|Text=0.1uF_25V_0402|Name=Comment
|RECORD=44|OwnerIndex=1756
|RECORD=45|OwnerIndex=1793|IndexInSheet=-1|UseComponentLibrary=T|ModelName=FP-0402-L_1_0_1-W_0_5_0_1-IPC_C|ModelType=PCBLIB|DatafileCount=1|ModelDatafileEntity0=FP-0402-L_1_0_1-W_0_5_0_1-IPC_C|ModelDatafileKind0=PCBLib|IsCurrent=T|DatalinksLocked=T|DatabaseDatalinksLocked=T
|RECORD=46|OwnerIndex=1794
|RECORD=48|OwnerIndex=1794
|RECORD=45|OwnerIndex=1793|IndexInSheet=-1|UseComponentLibrary=T|ModelName=FP-0402-L_1_0_1-W_0_5_0_1-IPC_B|ModelType=PCBLIB|DatafileCount=1|ModelDatafileEntity0=FP-0402-L_1_0_1-W_0_5_0_1-IPC_B|ModelDatafileKind0=PCBLib|DatalinksLocked=T|DatabaseDatalinksLocked=T
|RECORD=46|OwnerIndex=1797
|RECORD=48|OwnerIndex=1797
|RECORD=45|OwnerIndex=1793|IndexInSheet=-1|UseComponentLibrary=T|ModelName=FP-0402-L_1_0_1-W_0_5_0_1-MFG|ModelType=PCBLIB|DatafileCount=1|ModelDatafileEntity0=FP-0402-L_1_0_1-W_0_5_0_1-MFG|ModelDatafileKind0=PCBLib|DatalinksLocked=T|DatabaseDatalinksLocked=T
|RECORD=46|OwnerIndex=1800
|RECORD=48|OwnerIndex=1800
|RECORD=45|OwnerIndex=1793|IndexInSheet=-1|UseComponentLibrary=T|ModelName=FP-0402-L_1_0_1-W_0_5_0_1-IPC_A|ModelType=PCBLIB|DatafileCount=1|ModelDatafileEntity0=FP-0402-L_1_0_1-W_0_5_0_1-IPC_A|ModelDatafileKind0=PCBLib|DatalinksLocked=T|DatabaseDatalinksLocked=T
|RECORD=46|OwnerIndex=1803
|RECORD=48|OwnerIndex=1803
|RECORD=17|IndexInSheet=139|OwnerPartId=-1|ShowNetName=T|Location.X=400|Location.Y=870|Orientation=1|Color=128|FontID=1|Text=FTDI_VBUS
|RECORD=17|IndexInSheet=140|OwnerPartId=-1|ShowNetName=T|Location.X=60|Location.Y=580|Orientation=1|Color=128|FontID=1|Text=FTDI_VBUS
|RECORD=17|IndexInSheet=141|OwnerPartId=-1|Style=4|ShowNetName=T|Location.X=310|Location.Y=470|Orientation=3|Color=128|FontID=1|Text=GND
|RECORD=1|LibReference=b4654b650e69147ec39a6b967a45e02|ComponentDescription=None|PartCount=2|DisplayModeCount=1|IndexInSheet=142|OwnerPartId=-1|Location.X=70|Location.Y=520|CurrentPartId=1|LibraryPath=*|SourceLibraryName=Altium Content Vault|TargetFileName=*|AreaColor=11599871|Color=128|PartIDLocked=T|DesignItemId=CMP-14477-000104-2|AllPinCount=2
|RECORD=2|OwnerIndex=1809|OwnerPartId=1|Electrical=4|PinConglomerate=49|PinLength=7|Location.X=70|Location.Y=513|Name=1|Designator=1|PinPropagationDelay=0.000000E+000
|RECORD=2|OwnerIndex=1809|OwnerPartId=1|Electrical=4|PinConglomerate=51|PinLength=6|Location.X=70|Location.Y=506|Name=2|Designator=2|PinPropagationDelay=0.000000E+000
|RECORD=13|OwnerIndex=1809|IsNotAccesible=T|IndexInSheet=2|OwnerPartId=1|Location.X=80|Location.Y=513|Corner.X=60|Corner.Y=513|LineWidth=1|Color=16711680
|RECORD=13|OwnerIndex=1809|IsNotAccesible=T|IndexInSheet=3|OwnerPartId=1|Location.X=80|Location.Y=507|Corner.X=60|Corner.Y=507|LineWidth=1|Color=16711680
|RECORD=13|OwnerIndex=1809|IsNotAccesible=T|IndexInSheet=4|OwnerPartId=1|Location.X=70|Location.Y=513|Corner.X=70|Corner.Y=516|LineWidth=1|Color=16711680
|RECORD=13|OwnerIndex=1809|IsNotAccesible=T|IndexInSheet=5|OwnerPartId=1|Location.X=70|Location.Y=506|Corner.X=70|Corner.Y=505|LineWidth=1|Color=16711680
|RECORD=41|OwnerIndex=1809|IndexInSheet=6|OwnerPartId=-1|Location.X=59|Location.Y=522|Color=8388608|FontID=1|IsHidden=T|Text=Tape and Reel|Name=Packaging
|RECORD=41|OwnerIndex=1809|IndexInSheet=7|OwnerPartId=-1|Location.X=59|Location.Y=522|Color=8388608|FontID=1|IsHidden=T|Text=0.5mm|Name=Depth
|RECORD=41|OwnerIndex=1809|IndexInSheet=8|OwnerPartId=-1|Location.X=59|Location.Y=522|Color=8388608|FontID=1|IsHidden=T|Text=10%|Name=Tolerance
|RECORD=41|OwnerIndex=1809|IndexInSheet=9|OwnerPartId=-1|Location.X=59|Location.Y=522|Color=8388608|FontID=1|IsHidden=T|Text=Surface Mount|Name=Mount
|RECORD=41|OwnerIndex=1809|IndexInSheet=10|OwnerPartId=-1|Location.X=59|Location.Y=522|Color=8388608|FontID=1|IsHidden=T|Text=16V|Name=Voltage Rating
|RECORD=41|OwnerIndex=1809|IndexInSheet=11|OwnerPartId=-1|Location.X=59|Location.Y=522|Color=8388608|FontID=1|IsHidden=T|Text=0.022inch|Name=Thickness
|RECORD=41|OwnerIndex=1809|IndexInSheet=12|OwnerPartId=-1|Location.X=59|Location.Y=522|Color=8388608|FontID=1|IsHidden=T|Text=1|Name=Package Quantity
|RECORD=41|OwnerIndex=1809|IndexInSheet=13|OwnerPartId=-1|Location.X=59|Location.Y=522|Color=8388608|FontID=1|IsHidden=T|Text=-55°C|Name=Min Operating Temperature
|RECORD=41|OwnerIndex=1809|IndexInSheet=14|OwnerPartId=-1|Location.X=59|Location.Y=522|Color=8388608|FontID=1|IsHidden=T|Text=M|Name=Series
|RECORD=41|OwnerIndex=1809|IndexInSheet=15|OwnerPartId=-1|Location.X=59|Location.Y=522|Color=8388608|FontID=1|IsHidden=T|Text=16V|Name=Voltage Rating (DC)
|RECORD=41|OwnerIndex=1809|IndexInSheet=16|OwnerPartId=-1|Location.X=59|Location.Y=522|Color=8388608|FontID=1|IsHidden=T|Text=SMD/SMT|Name=Termination
|RECORD=41|OwnerIndex=1809|IndexInSheet=17|OwnerPartId=-1|Location.X=59|Location.Y=522|Color=8388608|FontID=1|IsHidden=T|Text=0402|Name=Case/Package
|RECORD=41|OwnerIndex=1809|IndexInSheet=18|OwnerPartId=-1|Location.X=59|Location.Y=522|Color=8388608|FontID=1|IsHidden=T|Text=X5R|Name=Dielectric
|RECORD=41|OwnerIndex=1809|IndexInSheet=19|OwnerPartId=-1|Location.X=59|Location.Y=522|Color=8388608|FontID=1|IsHidden=T|Text=2|Name=Number of Pins
|RECORD=41|OwnerIndex=1809|IndexInSheet=20|OwnerPartId=-1|Location.X=59|Location.Y=522|Color=8388608|FontID=1|IsHidden=T|Text=0402|Name=Case Code (Imperial)
|RECORD=41|OwnerIndex=1809|IndexInSheet=21|OwnerPartId=-1|Location.X=59|Location.Y=522|Color=8388608|FontID=1|IsHidden=T|Text=1uF|Name=Capacitance
|RECORD=41|OwnerIndex=1809|IndexInSheet=22|OwnerPartId=-1|Location.X=59|Location.Y=522|Color=8388608|FontID=1|IsHidden=T|Text=1mm|Name=Length
|RECORD=41|OwnerIndex=1809|IndexInSheet=23|OwnerPartId=-1|Location.X=59|Location.Y=522|Color=8388608|FontID=1|IsHidden=T|Text=Halogen Free|Name=Halogen Free
|RECORD=41|OwnerIndex=1809|IndexInSheet=24|OwnerPartId=-1|Location.X=59|Location.Y=522|Color=8388608|FontID=1|IsHidden=T|Text=1005|Name=Case Code (Metric)
|RECORD=41|OwnerIndex=1809|IndexInSheet=25|OwnerPartId=-1|Location.X=59|Location.Y=522|Color=8388608|FontID=1|IsHidden=T|Text=0.02inch|Name=Width
|RECORD=41|OwnerIndex=1809|IndexInSheet=26|OwnerPartId=-1|Location.X=59|Location.Y=522|Color=8388608|FontID=1|IsHidden=T|Text=Yes|Name=RoHS Compliant
|RECORD=41|OwnerIndex=1809|IndexInSheet=27|OwnerPartId=-1|Location.X=59|Location.Y=522|Color=8388608|FontID=1|IsHidden=T|Text=No|Name=Radiation Hardening
|RECORD=41|OwnerIndex=1809|IndexInSheet=28|OwnerPartId=-1|Location.X=59|Location.Y=522|Color=8388608|FontID=1|IsHidden=T|Text=85°C|Name=Max Operating Temperature
|RECORD=41|OwnerIndex=1809|IndexInSheet=29|OwnerPartId=-1|Location.X=59|Location.Y=522|Color=8388608|FontID=1|IsHidden=T|Text=0.5mm|Name=Height
|RECORD=41|OwnerIndex=1809|IndexInSheet=30|OwnerPartId=-1|Location.X=59|Location.Y=522|Color=8388608|FontID=1|IsHidden=T|Text=Flat|Name=Construction
|RECORD=34|OwnerIndex=1809|IndexInSheet=-1|OwnerPartId=-1|Location.X=55|Location.Y=500|Orientation=1|Color=8388608|FontID=2|Text=C114|Name=Designator|ReadOnlyState=1
|RECORD=41|OwnerIndex=1809|IndexInSheet=-1|OwnerPartId=1|Location.X=90|Location.Y=485|Orientation=1|Color=8388608|FontID=2|Text=1uF_16V_0402|Name=Comment
|RECORD=44|OwnerIndex=1809
|RECORD=45|OwnerIndex=1845|IndexInSheet=-1|UseComponentLibrary=T|ModelName=FP-0402-L_1_0_0_05-W_0_5-IPC_A|ModelType=PCBLIB|DatafileCount=1|ModelDatafileEntity0=FP-0402-L_1_0_0_05-W_0_5-IPC_A|ModelDatafileKind0=PCBLib|IsCurrent=T|DatalinksLocked=T|DatabaseDatalinksLocked=T
|RECORD=46|OwnerIndex=1846
|RECORD=48|OwnerIndex=1846
|RECORD=45|OwnerIndex=1845|IndexInSheet=-1|UseComponentLibrary=T|ModelName=EMK105BJ105_V-F|ModelType=SIM|IsCurrent=T|DatalinksLocked=T|DatabaseDatalinksLocked=T
|RECORD=46|OwnerIndex=1849
|RECORD=48|OwnerIndex=1849
|RECORD=41|OwnerIndex=1851|IndexInSheet=-1|OwnerPartId=-1|Color=8388608|FontID=1|IsHidden=T|Text=General|Name=Kind
|RECORD=41|OwnerIndex=1851|IndexInSheet=-1|OwnerPartId=-1|Color=8388608|FontID=1|IsHidden=T|Text=Spice Subcircuit|Name=SubKind
|RECORD=41|OwnerIndex=1851|IndexInSheet=-1|OwnerPartId=-1|Color=8388608|FontID=1|IsHidden=T|Name=Spice Prefix
|RECORD=41|OwnerIndex=1851|IndexInSheet=-1|OwnerPartId=-1|Color=8388608|FontID=1|IsHidden=T|Name=Excluded Parts
|RECORD=41|OwnerIndex=1851|IndexInSheet=-1|OwnerPartId=-1|Color=8388608|FontID=1|IsHidden=T|Name=Netlist
|RECORD=41|OwnerIndex=1851|IndexInSheet=-1|OwnerPartId=-1|Color=8388608|FontID=1|IsHidden=T|Text=document_sim_cache\LIOYUQKN\0|Name=SimulationCacheLocation|ReadOnlyState=3
|RECORD=45|OwnerIndex=1845|IndexInSheet=-1|UseComponentLibrary=T|ModelName=FP-0402-L_1_0_0_05-W_0_5-IPC_B|ModelType=PCBLIB|DatafileCount=1|ModelDatafileEntity0=FP-0402-L_1_0_0_05-W_0_5-IPC_B|ModelDatafileKind0=PCBLib|DatalinksLocked=T|DatabaseDatalinksLocked=T
|RECORD=46|OwnerIndex=1858
|RECORD=48|OwnerIndex=1858
|RECORD=45|OwnerIndex=1845|IndexInSheet=-1|UseComponentLibrary=T|ModelName=FP-0402-L_1_0_0_05-W_0_5-IPC_C|ModelType=PCBLIB|DatafileCount=1|ModelDatafileEntity0=FP-0402-L_1_0_0_05-W_0_5-IPC_C|ModelDatafileKind0=PCBLib|DatalinksLocked=T|DatabaseDatalinksLocked=T
|RECORD=46|OwnerIndex=1861
|RECORD=48|OwnerIndex=1861
|RECORD=45|OwnerIndex=1845|IndexInSheet=-1|UseComponentLibrary=T|ModelName=FP-0402-L_1_0_0_05-W_0_5-MFG|ModelType=PCBLIB|DatafileCount=1|ModelDatafileEntity0=FP-0402-L_1_0_0_05-W_0_5-MFG|ModelDatafileKind0=PCBLib|DatalinksLocked=T|DatabaseDatalinksLocked=T
|RECORD=46|OwnerIndex=1864
|RECORD=48|OwnerIndex=1864
|RECORD=41|IndexInSheet=143|OwnerPartId=-1|Color=8388608|FontID=1|IsHidden=T|Text=|Name=SPICEModelCacheLIOYUQKN|ReadOnlyState=3
|RECORD=17|IndexInSheet=144|OwnerPartId=-1|Style=4|ShowNetName=T|Location.X=70|Location.Y=470|Orientation=3|Color=128|FontID=1|Text=GND
|RECORD=1|LibReference=b4654b650e69147ec39a6b967a45e02|ComponentDescription=General Purpose Ceramic Capacitor, 0402, 100nF, 10%, X7R, 15%, 25V|PartCount=2|DisplayModeCount=1|IndexInSheet=145|OwnerPartId=-1|Location.X=430|Location.Y=540|CurrentPartId=1|LibraryPath=*|SourceLibraryName=Altium Content Vault|TargetFileName=*|AreaColor=11599871|Color=128|PartIDLocked=T|DesignItemId=CMP-2008-02519-2|AllPinCount=2
|RECORD=2|OwnerIndex=1869|OwnerPartId=1|Electrical=4|PinConglomerate=49|PinLength=7|Location.X=430|Location.Y=533|Name=1|Designator=1|PinPropagationDelay=0.000000E+000
|RECORD=2|OwnerIndex=1869|OwnerPartId=1|Electrical=4|PinConglomerate=51|PinLength=6|Location.X=430|Location.Y=526|Name=2|Designator=2|PinPropagationDelay=0.000000E+000
|RECORD=13|OwnerIndex=1869|IsNotAccesible=T|IndexInSheet=2|OwnerPartId=1|Location.X=440|Location.Y=533|Corner.X=420|Corner.Y=533|LineWidth=1|Color=16711680
|RECORD=13|OwnerIndex=1869|IsNotAccesible=T|IndexInSheet=3|OwnerPartId=1|Location.X=440|Location.Y=527|Corner.X=420|Corner.Y=527|LineWidth=1|Color=16711680
|RECORD=13|OwnerIndex=1869|IsNotAccesible=T|IndexInSheet=4|OwnerPartId=1|Location.X=430|Location.Y=533|Corner.X=430|Corner.Y=536|LineWidth=1|Color=16711680
|RECORD=13|OwnerIndex=1869|IsNotAccesible=T|IndexInSheet=5|OwnerPartId=1|Location.X=430|Location.Y=526|Corner.X=430|Corner.Y=525|LineWidth=1|Color=16711680
|RECORD=41|OwnerIndex=1869|IndexInSheet=6|OwnerPartId=-1|Location.X=419|Location.Y=542|Color=8388608|FontID=1|IsHidden=T|Text=1|Name=Package Quantity
|RECORD=41|OwnerIndex=1869|IndexInSheet=7|OwnerPartId=-1|Location.X=419|Location.Y=542|Color=8388608|FontID=1|IsHidden=T|Text=100nF|Name=Capacitance
|RECORD=41|OwnerIndex=1869|IndexInSheet=8|OwnerPartId=-1|Location.X=419|Location.Y=542|Color=8388608|FontID=1|IsHidden=T|Text=-55°C|Name=Min Operating Temperature
|RECORD=41|OwnerIndex=1869|IndexInSheet=9|OwnerPartId=-1|Location.X=419|Location.Y=542|Color=8388608|FontID=1|IsHidden=T|Text=25V|Name=Voltage
|RECORD=41|OwnerIndex=1869|IndexInSheet=10|OwnerPartId=-1|Location.X=419|Location.Y=542|Color=8388608|FontID=1|IsHidden=T|Text=25V|Name=Voltage Rating
|RECORD=41|OwnerIndex=1869|IndexInSheet=11|OwnerPartId=-1|Location.X=419|Location.Y=542|Color=8388608|FontID=1|IsHidden=T|Text=Flat|Name=Construction
|RECORD=41|OwnerIndex=1869|IndexInSheet=12|OwnerPartId=-1|Location.X=419|Location.Y=542|Color=8388608|FontID=1|IsHidden=T|Text=125°C|Name=Max Operating Temperature
|RECORD=41|OwnerIndex=1869|IndexInSheet=13|OwnerPartId=-1|Location.X=419|Location.Y=542|Color=8388608|FontID=1|IsHidden=T|Text=No|Name=Radiation Hardening
|RECORD=41|OwnerIndex=1869|IndexInSheet=14|OwnerPartId=-1|Location.X=419|Location.Y=542|Color=8388608|FontID=1|IsHidden=T|Text=0.5mm|Name=Depth
|RECORD=41|OwnerIndex=1869|IndexInSheet=15|OwnerPartId=-1|Location.X=419|Location.Y=542|Color=8388608|FontID=1|IsHidden=T|Text=0.022inch|Name=Thickness
|RECORD=41|OwnerIndex=1869|IndexInSheet=16|OwnerPartId=-1|Location.X=419|Location.Y=542|Color=8388608|FontID=1|IsHidden=T|Text=25V|Name=Voltage Rating (DC)
|RECORD=41|OwnerIndex=1869|IndexInSheet=17|OwnerPartId=-1|Location.X=419|Location.Y=542|Color=8388608|FontID=1|IsHidden=T|Text=2|Name=Number of Pins
|RECORD=41|OwnerIndex=1869|IndexInSheet=18|OwnerPartId=-1|Location.X=419|Location.Y=542|Color=8388608|FontID=1|IsHidden=T|Text=Lead Free|Name=Lead Free
|RECORD=41|OwnerIndex=1869|IndexInSheet=19|OwnerPartId=-1|Location.X=419|Location.Y=542|Color=8388608|FontID=1|IsHidden=T|Text=-|Name=Series
|RECORD=41|OwnerIndex=1869|IndexInSheet=20|OwnerPartId=-1|Location.X=419|Location.Y=542|Color=8388608|FontID=1|IsHidden=T|Text=No SVHC|Name=REACH SVHC
|RECORD=41|OwnerIndex=1869|IndexInSheet=21|OwnerPartId=-1|Location.X=419|Location.Y=542|Color=8388608|FontID=1|IsHidden=T|Text=1mm|Name=Length
|RECORD=41|OwnerIndex=1869|IndexInSheet=22|OwnerPartId=-1|Location.X=419|Location.Y=542|Color=8388608|FontID=1|IsHidden=T|Text=X7R|Name=Dielectric
|RECORD=41|OwnerIndex=1869|IndexInSheet=23|OwnerPartId=-1|Location.X=419|Location.Y=542|Color=8388608|FontID=1|IsHidden=T|Text=Yes|Name=RoHS Compliant
|RECORD=41|OwnerIndex=1869|IndexInSheet=24|OwnerPartId=-1|Location.X=419|Location.Y=542|Color=8388608|FontID=1|IsHidden=T|Text=Surface Mount|Name=Mount
|RECORD=41|OwnerIndex=1869|IndexInSheet=25|OwnerPartId=-1|Location.X=419|Location.Y=542|Color=8388608|FontID=1|IsHidden=T|Text=Tape and Reel|Name=Packaging
|RECORD=41|OwnerIndex=1869|IndexInSheet=26|OwnerPartId=-1|Location.X=419|Location.Y=542|Color=8388608|FontID=1|IsHidden=T|Text=0402|Name=Case/Package
|RECORD=41|OwnerIndex=1869|IndexInSheet=27|OwnerPartId=-1|Location.X=419|Location.Y=542|Color=8388608|FontID=1|IsHidden=T|Text=0402|Name=Case Code (Imperial)
|RECORD=41|OwnerIndex=1869|IndexInSheet=28|OwnerPartId=-1|Location.X=419|Location.Y=542|Color=8388608|FontID=1|IsHidden=T|Text=SMD/SMT|Name=Termination
|RECORD=41|OwnerIndex=1869|IndexInSheet=29|OwnerPartId=-1|Location.X=419|Location.Y=542|Color=8388608|FontID=1|IsHidden=T|Text=0.02inch|Name=Width
|RECORD=41|OwnerIndex=1869|IndexInSheet=30|OwnerPartId=-1|Location.X=419|Location.Y=542|Color=8388608|FontID=1|IsHidden=T|Text=1005|Name=Case Code (Metric)
|RECORD=41|OwnerIndex=1869|IndexInSheet=31|OwnerPartId=-1|Location.X=419|Location.Y=542|Color=8388608|FontID=1|IsHidden=T|Text=10%|Name=Tolerance
|RECORD=34|OwnerIndex=1869|IndexInSheet=-1|OwnerPartId=-1|Location.X=420|Location.Y=520|Orientation=1|Color=8388608|FontID=2|Text=C112|Name=Designator|ReadOnlyState=1
|RECORD=41|OwnerIndex=1869|IndexInSheet=-1|OwnerPartId=1|Location.X=450|Location.Y=505|Orientation=1|Color=8388608|FontID=2|Text=0.1uF_25V_0402|Name=Comment
|RECORD=44|OwnerIndex=1869
|RECORD=45|OwnerIndex=1906|IndexInSheet=-1|UseComponentLibrary=T|ModelName=FP-0402-L_1_0_1-W_0_5_0_1-IPC_C|ModelType=PCBLIB|DatafileCount=1|ModelDatafileEntity0=FP-0402-L_1_0_1-W_0_5_0_1-IPC_C|ModelDatafileKind0=PCBLib|IsCurrent=T|DatalinksLocked=T|DatabaseDatalinksLocked=T
|RECORD=46|OwnerIndex=1907
|RECORD=48|OwnerIndex=1907
|RECORD=45|OwnerIndex=1906|IndexInSheet=-1|UseComponentLibrary=T|ModelName=FP-0402-L_1_0_1-W_0_5_0_1-IPC_B|ModelType=PCBLIB|DatafileCount=1|ModelDatafileEntity0=FP-0402-L_1_0_1-W_0_5_0_1-IPC_B|ModelDatafileKind0=PCBLib|DatalinksLocked=T|DatabaseDatalinksLocked=T
|RECORD=46|OwnerIndex=1910
|RECORD=48|OwnerIndex=1910
|RECORD=45|OwnerIndex=1906|IndexInSheet=-1|UseComponentLibrary=T|ModelName=FP-0402-L_1_0_1-W_0_5_0_1-MFG|ModelType=PCBLIB|DatafileCount=1|ModelDatafileEntity0=FP-0402-L_1_0_1-W_0_5_0_1-MFG|ModelDatafileKind0=PCBLib|DatalinksLocked=T|DatabaseDatalinksLocked=T
|RECORD=46|OwnerIndex=1913
|RECORD=48|OwnerIndex=1913
|RECORD=45|OwnerIndex=1906|IndexInSheet=-1|UseComponentLibrary=T|ModelName=FP-0402-L_1_0_1-W_0_5_0_1-IPC_A|ModelType=PCBLIB|DatafileCount=1|ModelDatafileEntity0=FP-0402-L_1_0_1-W_0_5_0_1-IPC_A|ModelDatafileKind0=PCBLib|DatalinksLocked=T|DatabaseDatalinksLocked=T
|RECORD=46|OwnerIndex=1916
|RECORD=48|OwnerIndex=1916
|RECORD=1|LibReference=b4654b650e69147ec39a6b967a45e02|ComponentDescription=None|PartCount=2|DisplayModeCount=1|IndexInSheet=146|OwnerPartId=-1|Location.X=390|Location.Y=540|CurrentPartId=1|LibraryPath=*|SourceLibraryName=Altium Content Vault|TargetFileName=*|AreaColor=11599871|Color=128|PartIDLocked=T|DesignItemId=CMP-14477-000104-2|AllPinCount=2
|RECORD=2|OwnerIndex=1919|OwnerPartId=1|Electrical=4|PinConglomerate=49|PinLength=7|Location.X=390|Location.Y=533|Name=1|Designator=1|PinPropagationDelay=0.000000E+000
|RECORD=2|OwnerIndex=1919|OwnerPartId=1|Electrical=4|PinConglomerate=51|PinLength=6|Location.X=390|Location.Y=526|Name=2|Designator=2|PinPropagationDelay=0.000000E+000
|RECORD=13|OwnerIndex=1919|IsNotAccesible=T|IndexInSheet=2|OwnerPartId=1|Location.X=400|Location.Y=533|Corner.X=380|Corner.Y=533|LineWidth=1|Color=16711680
|RECORD=13|OwnerIndex=1919|IsNotAccesible=T|IndexInSheet=3|OwnerPartId=1|Location.X=400|Location.Y=527|Corner.X=380|Corner.Y=527|LineWidth=1|Color=16711680
|RECORD=13|OwnerIndex=1919|IsNotAccesible=T|IndexInSheet=4|OwnerPartId=1|Location.X=390|Location.Y=533|Corner.X=390|Corner.Y=536|LineWidth=1|Color=16711680
|RECORD=13|OwnerIndex=1919|IsNotAccesible=T|IndexInSheet=5|OwnerPartId=1|Location.X=390|Location.Y=526|Corner.X=390|Corner.Y=525|LineWidth=1|Color=16711680
|RECORD=41|OwnerIndex=1919|IndexInSheet=6|OwnerPartId=-1|Location.X=379|Location.Y=542|Color=8388608|FontID=1|IsHidden=T|Text=Tape and Reel|Name=Packaging
|RECORD=41|OwnerIndex=1919|IndexInSheet=7|OwnerPartId=-1|Location.X=379|Location.Y=542|Color=8388608|FontID=1|IsHidden=T|Text=0.5mm|Name=Depth
|RECORD=41|OwnerIndex=1919|IndexInSheet=8|OwnerPartId=-1|Location.X=379|Location.Y=542|Color=8388608|FontID=1|IsHidden=T|Text=10%|Name=Tolerance
|RECORD=41|OwnerIndex=1919|IndexInSheet=9|OwnerPartId=-1|Location.X=379|Location.Y=542|Color=8388608|FontID=1|IsHidden=T|Text=Surface Mount|Name=Mount
|RECORD=41|OwnerIndex=1919|IndexInSheet=10|OwnerPartId=-1|Location.X=379|Location.Y=542|Color=8388608|FontID=1|IsHidden=T|Text=16V|Name=Voltage Rating
|RECORD=41|OwnerIndex=1919|IndexInSheet=11|OwnerPartId=-1|Location.X=379|Location.Y=542|Color=8388608|FontID=1|IsHidden=T|Text=0.022inch|Name=Thickness
|RECORD=41|OwnerIndex=1919|IndexInSheet=12|OwnerPartId=-1|Location.X=379|Location.Y=542|Color=8388608|FontID=1|IsHidden=T|Text=1|Name=Package Quantity
|RECORD=41|OwnerIndex=1919|IndexInSheet=13|OwnerPartId=-1|Location.X=379|Location.Y=542|Color=8388608|FontID=1|IsHidden=T|Text=-55°C|Name=Min Operating Temperature
|RECORD=41|OwnerIndex=1919|IndexInSheet=14|OwnerPartId=-1|Location.X=379|Location.Y=542|Color=8388608|FontID=1|IsHidden=T|Text=M|Name=Series
|RECORD=41|OwnerIndex=1919|IndexInSheet=15|OwnerPartId=-1|Location.X=379|Location.Y=542|Color=8388608|FontID=1|IsHidden=T|Text=16V|Name=Voltage Rating (DC)
|RECORD=41|OwnerIndex=1919|IndexInSheet=16|OwnerPartId=-1|Location.X=379|Location.Y=542|Color=8388608|FontID=1|IsHidden=T|Text=SMD/SMT|Name=Termination
|RECORD=41|OwnerIndex=1919|IndexInSheet=17|OwnerPartId=-1|Location.X=379|Location.Y=542|Color=8388608|FontID=1|IsHidden=T|Text=0402|Name=Case/Package
|RECORD=41|OwnerIndex=1919|IndexInSheet=18|OwnerPartId=-1|Location.X=379|Location.Y=542|Color=8388608|FontID=1|IsHidden=T|Text=X5R|Name=Dielectric
|RECORD=41|OwnerIndex=1919|IndexInSheet=19|OwnerPartId=-1|Location.X=379|Location.Y=542|Color=8388608|FontID=1|IsHidden=T|Text=2|Name=Number of Pins
|RECORD=41|OwnerIndex=1919|IndexInSheet=20|OwnerPartId=-1|Location.X=379|Location.Y=542|Color=8388608|FontID=1|IsHidden=T|Text=0402|Name=Case Code (Imperial)
|RECORD=41|OwnerIndex=1919|IndexInSheet=21|OwnerPartId=-1|Location.X=379|Location.Y=542|Color=8388608|FontID=1|IsHidden=T|Text=1uF|Name=Capacitance
|RECORD=41|OwnerIndex=1919|IndexInSheet=22|OwnerPartId=-1|Location.X=379|Location.Y=542|Color=8388608|FontID=1|IsHidden=T|Text=1mm|Name=Length
|RECORD=41|OwnerIndex=1919|IndexInSheet=23|OwnerPartId=-1|Location.X=379|Location.Y=542|Color=8388608|FontID=1|IsHidden=T|Text=Halogen Free|Name=Halogen Free
|RECORD=41|OwnerIndex=1919|IndexInSheet=24|OwnerPartId=-1|Location.X=379|Location.Y=542|Color=8388608|FontID=1|IsHidden=T|Text=1005|Name=Case Code (Metric)
|RECORD=41|OwnerIndex=1919|IndexInSheet=25|OwnerPartId=-1|Location.X=379|Location.Y=542|Color=8388608|FontID=1|IsHidden=T|Text=0.02inch|Name=Width
|RECORD=41|OwnerIndex=1919|IndexInSheet=26|OwnerPartId=-1|Location.X=379|Location.Y=542|Color=8388608|FontID=1|IsHidden=T|Text=Yes|Name=RoHS Compliant
|RECORD=41|OwnerIndex=1919|IndexInSheet=27|OwnerPartId=-1|Location.X=379|Location.Y=542|Color=8388608|FontID=1|IsHidden=T|Text=No|Name=Radiation Hardening
|RECORD=41|OwnerIndex=1919|IndexInSheet=28|OwnerPartId=-1|Location.X=379|Location.Y=542|Color=8388608|FontID=1|IsHidden=T|Text=85°C|Name=Max Operating Temperature
|RECORD=41|OwnerIndex=1919|IndexInSheet=29|OwnerPartId=-1|Location.X=379|Location.Y=542|Color=8388608|FontID=1|IsHidden=T|Text=0.5mm|Name=Height
|RECORD=41|OwnerIndex=1919|IndexInSheet=30|OwnerPartId=-1|Location.X=379|Location.Y=542|Color=8388608|FontID=1|IsHidden=T|Text=Flat|Name=Construction
|RECORD=34|OwnerIndex=1919|IndexInSheet=-1|OwnerPartId=-1|Location.X=375|Location.Y=520|Orientation=1|Color=8388608|FontID=2|Text=C111|Name=Designator|ReadOnlyState=1
|RECORD=41|OwnerIndex=1919|IndexInSheet=-1|OwnerPartId=1|Location.X=410|Location.Y=505|Orientation=1|Color=8388608|FontID=2|Text=1uF_16V_0402|Name=Comment
|RECORD=44|OwnerIndex=1919
|RECORD=45|OwnerIndex=1955|IndexInSheet=-1|UseComponentLibrary=T|ModelName=FP-0402-L_1_0_0_05-W_0_5-IPC_A|ModelType=PCBLIB|DatafileCount=1|ModelDatafileEntity0=FP-0402-L_1_0_0_05-W_0_5-IPC_A|ModelDatafileKind0=PCBLib|IsCurrent=T|DatalinksLocked=T|DatabaseDatalinksLocked=T
|RECORD=46|OwnerIndex=1956
|RECORD=48|OwnerIndex=1956
|RECORD=45|OwnerIndex=1955|IndexInSheet=-1|UseComponentLibrary=T|ModelName=EMK105BJ105_V-F|ModelType=SIM|IsCurrent=T|DatalinksLocked=T|DatabaseDatalinksLocked=T
|RECORD=46|OwnerIndex=1959
|RECORD=48|OwnerIndex=1959
|RECORD=41|OwnerIndex=1961|IndexInSheet=-1|OwnerPartId=-1|Color=8388608|FontID=1|IsHidden=T|Text=General|Name=Kind
|RECORD=41|OwnerIndex=1961|IndexInSheet=-1|OwnerPartId=-1|Color=8388608|FontID=1|IsHidden=T|Text=Spice Subcircuit|Name=SubKind
|RECORD=41|OwnerIndex=1961|IndexInSheet=-1|OwnerPartId=-1|Color=8388608|FontID=1|IsHidden=T|Name=Spice Prefix
|RECORD=41|OwnerIndex=1961|IndexInSheet=-1|OwnerPartId=-1|Color=8388608|FontID=1|IsHidden=T|Name=Excluded Parts
|RECORD=41|OwnerIndex=1961|IndexInSheet=-1|OwnerPartId=-1|Color=8388608|FontID=1|IsHidden=T|Name=Netlist
|RECORD=41|OwnerIndex=1961|IndexInSheet=-1|OwnerPartId=-1|Color=8388608|FontID=1|IsHidden=T|Text=document_sim_cache\LIOYUQKN\0|Name=SimulationCacheLocation|ReadOnlyState=3
|RECORD=45|OwnerIndex=1955|IndexInSheet=-1|UseComponentLibrary=T|ModelName=FP-0402-L_1_0_0_05-W_0_5-IPC_B|ModelType=PCBLIB|DatafileCount=1|ModelDatafileEntity0=FP-0402-L_1_0_0_05-W_0_5-IPC_B|ModelDatafileKind0=PCBLib|DatalinksLocked=T|DatabaseDatalinksLocked=T
|RECORD=46|OwnerIndex=1968
|RECORD=48|OwnerIndex=1968
|RECORD=45|OwnerIndex=1955|IndexInSheet=-1|UseComponentLibrary=T|ModelName=FP-0402-L_1_0_0_05-W_0_5-IPC_C|ModelType=PCBLIB|DatafileCount=1|ModelDatafileEntity0=FP-0402-L_1_0_0_05-W_0_5-IPC_C|ModelDatafileKind0=PCBLib|DatalinksLocked=T|DatabaseDatalinksLocked=T
|RECORD=46|OwnerIndex=1971
|RECORD=48|OwnerIndex=1971
|RECORD=45|OwnerIndex=1955|IndexInSheet=-1|UseComponentLibrary=T|ModelName=FP-0402-L_1_0_0_05-W_0_5-MFG|ModelType=PCBLIB|DatafileCount=1|ModelDatafileEntity0=FP-0402-L_1_0_0_05-W_0_5-MFG|ModelDatafileKind0=PCBLib|DatalinksLocked=T|DatabaseDatalinksLocked=T
|RECORD=46|OwnerIndex=1974
|RECORD=48|OwnerIndex=1974
|RECORD=17|IndexInSheet=147|OwnerPartId=-1|Style=4|ShowNetName=T|Location.X=390|Location.Y=490|Orientation=3|Color=128|FontID=1|Text=GND
|RECORD=17|IndexInSheet=148|OwnerPartId=-1|ShowNetName=T|Location.X=430|Location.Y=580|Orientation=1|Color=128|FontID=1|Text=FTDI_P3V3
|RECORD=1|LibReference=IC_TPS2116DRLR|ComponentDescription=1.6-V to 5.5-V, 40-m?, 2.5-A, low-IQ, priority power multiplexer 8-SOT-5X3 -40 to 125|PartCount=2|DisplayModeCount=1|IndexInSheet=149|OwnerPartId=-1|Location.X=730|Location.Y=540|CurrentPartId=1|LibraryPath=*|SourceLibraryName=LotusSound.IntLib|TargetFileName=*|AreaColor=11599871|Color=128|PartIDLocked=T|DesignItemId=IC_TPS2116DRLR|AllPinCount=8
|RECORD=41|OwnerIndex=1979|OwnerPartId=-1|Location.X=730|Location.Y=540|Color=8388608|FontID=3|IsHidden=T|Text=https://www.snapeda.com/parts/TPS2116DRLR/Texas%20Instruments/view-part/5674360/?ref=eda|Name=Check_prices
|RECORD=41|OwnerIndex=1979|IndexInSheet=1|OwnerPartId=-1|Location.X=730|Location.Y=540|Color=8388608|FontID=1|IsHidden=T|Text=TPS2116DRLR|Name=MP
|RECORD=41|OwnerIndex=1979|IndexInSheet=2|OwnerPartId=-1|Location.X=730|Location.Y=540|Color=8388608|FontID=1|IsHidden=T|Text=Package|Name=Package
|RECORD=41|OwnerIndex=1979|IndexInSheet=3|OwnerPartId=-1|Location.X=730|Location.Y=540|Color=8388608|FontID=1|IsHidden=T|Text=None|Name=Price
|RECORD=41|OwnerIndex=1979|IndexInSheet=4|OwnerPartId=-1|Location.X=730|Location.Y=540|Color=8388608|FontID=1|IsHidden=T|Text=No availability data|Name=Availability
|RECORD=41|OwnerIndex=1979|IndexInSheet=5|OwnerPartId=-1|Location.X=730|Location.Y=540|Color=8388608|FontID=1|IsHidden=T|Text=Texas Instruments|Name=MF
|RECORD=41|OwnerIndex=1979|IndexInSheet=6|OwnerPartId=-1|Location.X=730|Location.Y=540|Color=8388608|FontID=3|IsHidden=T|Text=https://www.snapeda.com/parts/TPS2116DRLR/Texas%20Instruments/view-part/5674360/?ref=snap|Name=SnapEDA_Link
|RECORD=41|OwnerIndex=1979|IndexInSheet=7|OwnerPartId=-1|Location.X=730|Location.Y=540|Color=8388608|FontID=1|IsHidden=T|Text=*|Name=Value
|RECORD=41|OwnerIndex=1979|IndexInSheet=8|OwnerPartId=-1|Location.X=658|Location.Y=580|Color=8388608|FontID=1|IsHidden=T|Text=LCSC|Name=Supplier 1|ReadOnlyState=3
|RECORD=41|OwnerIndex=1979|IndexInSheet=9|OwnerPartId=-1|Location.X=658|Location.Y=590|Color=8388608|FontID=1|IsHidden=T|Text=Texas Instruments|Name=Manufacturer
|RECORD=41|OwnerIndex=1979|IndexInSheet=10|OwnerPartId=-1|Location.X=658|Location.Y=590|Color=8388608|FontID=1|IsHidden=T|Text=TPS2116DRLR|Name=Manufacturer Part Number
|RECORD=41|OwnerIndex=1979|IndexInSheet=11|OwnerPartId=-1|Location.X=658|Location.Y=590|Color=8388608|FontID=1|IsHidden=T|Text=Yes|Name=RoHS
|RECORD=41|OwnerIndex=1979|IndexInSheet=12|OwnerPartId=-1|Location.X=658|Location.Y=590|Color=8388608|FontID=1|IsHidden=T|Text=Voltage Supervisors|Name=Category
|RECORD=41|OwnerIndex=1979|IndexInSheet=13|OwnerPartId=-1|Location.X=658|Location.Y=590|Color=8388608|FontID=1|IsHidden=T|Text=562|Name=Stock 1|ReadOnlyState=3
|RECORD=41|OwnerIndex=1979|IndexInSheet=14|OwnerPartId=-1|Location.X=658|Location.Y=590|Color=8388608|FontID=1|IsHidden=T|Text=1=0.6651, 10=0.5457, 30=0.4853, 100=0.4264, 500=0.3914, 1000=0.3723 (USD)|Name=Pricing 1|ReadOnlyState=3
|RECORD=14|OwnerIndex=1979|IsNotAccesible=T|IndexInSheet=15|OwnerPartId=1|Location.X=680|Location.Y=490|Corner.X=780|Corner.Y=580|Color=128|AreaColor=11599871|IsSolid=T
|RECORD=2|OwnerIndex=1979|OwnerPartId=1|FormalType=1|Electrical=4|PinConglomerate=58|PinLength=20|Location.X=680|Location.Y=570|Name=VIN1|Designator=3|SwapIDPart=Ž&Ž||PinPropagationDelay=0.000000E+000
|RECORD=2|OwnerIndex=1979|OwnerPartId=1|FormalType=1|Electrical=4|PinConglomerate=58|PinLength=20|Location.X=680|Location.Y=560|Name=VIN2|Designator=6|SwapIDPart=Ž&Ž||PinPropagationDelay=0.000000E+000
|RECORD=2|OwnerIndex=1979|OwnerPartId=1|FormalType=1|Electrical=4|PinConglomerate=58|PinLength=20|Location.X=680|Location.Y=540|Name=MODE|Designator=5|SwapIDPart=Ž&Ž||PinPropagationDelay=0.000000E+000
|RECORD=2|OwnerIndex=1979|OwnerPartId=1|FormalType=1|Electrical=4|PinConglomerate=58|PinLength=20|Location.X=680|Location.Y=530|Name=PR1|Designator=4|SwapIDPart=Ž&Ž||PinPropagationDelay=0.000000E+000
|RECORD=2|OwnerIndex=1979|OwnerPartId=1|FormalType=1|Electrical=4|PinConglomerate=56|PinLength=20|Location.X=780|Location.Y=570|Name=VOUT|Designator=2|SwapIDPart=Ž&Ž||PinPropagationDelay=0.000000E+000
|RECORD=2|OwnerIndex=1979|OwnerPartId=1|FormalType=1|Electrical=4|PinConglomerate=56|PinLength=20|Location.X=780|Location.Y=560|Name=VOUT|Designator=7|SwapIDPart=Ž&Ž||PinPropagationDelay=0.000000E+000
|RECORD=2|OwnerIndex=1979|OwnerPartId=1|FormalType=1|Electrical=4|PinConglomerate=56|PinLength=20|Location.X=780|Location.Y=530|Name=ST|Designator=8|SwapIDPart=Ž&Ž||PinPropagationDelay=0.000000E+000
|RECORD=2|OwnerIndex=1979|OwnerPartId=1|FormalType=1|Electrical=4|PinConglomerate=56|PinLength=20|Location.X=780|Location.Y=500|Name=GND|Designator=1|SwapIDPart=Ž&Ž||PinPropagationDelay=0.000000E+000
|RECORD=41|OwnerIndex=1979|IndexInSheet=24|OwnerPartId=-1|Location.X=658|Location.Y=580|Color=8388608|FontID=1|IsHidden=T|Text=C3235557|Name=Supplier Part Number 1|ReadOnlyState=3
|RECORD=34|OwnerIndex=1979|IndexInSheet=-1|OwnerPartId=-1|Location.X=680|Location.Y=580|Color=8388608|FontID=1|Text=U32|Name=Designator|ReadOnlyState=1
|RECORD=41|OwnerIndex=1979|IndexInSheet=-1|OwnerPartId=-1|Location.X=680|Location.Y=480|Color=8388608|FontID=1|Text=TPS2116DRLR|Name=Comment
|RECORD=44|OwnerIndex=1979
|RECORD=45|OwnerIndex=2015|IndexInSheet=-1|UseComponentLibrary=T|ModelName=IC_TPS2116|ModelType=PCBLIB|DatafileCount=1|ModelDatafileEntity0=IC_TPS2116|ModelDatafileKind0=PCBLib|IsCurrent=T|DatalinksLocked=T|DatabaseDatalinksLocked=T|IntegratedModel=T|DatabaseModel=T
|RECORD=46|OwnerIndex=2016
|RECORD=48|OwnerIndex=2016
|RECORD=17|IndexInSheet=150|OwnerPartId=-1|ShowNetName=T|Location.X=650|Location.Y=580|Orientation=1|Color=128|FontID=1|Text=FTDI_P3V3
|RECORD=17|IndexInSheet=151|OwnerPartId=-1|ShowNetName=T|Location.X=600|Location.Y=580|Orientation=1|Color=128|FontID=1|Text=+3.3V
|RECORD=1|LibReference=RES|PartCount=2|DisplayModeCount=2|IndexInSheet=152|OwnerPartId=-1|Location.X=570|Location.Y=530|Orientation=1|CurrentPartId=1|SourceLibraryName=Altium Content Vault|TargetFileName=*|AreaColor=11599871|Color=128|PartIDLocked=F|DesignItemId=CMP-2002-00433-1|AllPinCount=2
|RECORD=2|OwnerIndex=2021|OwnerPartId=1|OwnerPartDisplayMode=1|FormalType=1|Electrical=4|PinConglomerate=33|PinLength=10|Location.X=580|Location.Y=550|Name=2|Designator=2|PinPropagationDelay=0.000000E+000
|RECORD=2|OwnerIndex=2021|OwnerPartId=1|OwnerPartDisplayMode=1|FormalType=1|Electrical=4|PinConglomerate=35|PinLength=10|Location.X=580|Location.Y=530|Name=1|Designator=1|PinPropagationDelay=0.000000E+000
|RECORD=14|OwnerIndex=2021|IsNotAccesible=T|IndexInSheet=2|OwnerPartId=1|OwnerPartDisplayMode=1|Location.X=576|Location.Y=530|Corner.X=584|Corner.Y=550|LineWidth=1|Color=16711680|AreaColor=11599871
|RECORD=2|OwnerIndex=2021|OwnerPartId=1|FormalType=1|Electrical=4|PinConglomerate=33|PinLength=10|Location.X=580|Location.Y=550|Name=2|Designator=2|PinPropagationDelay=0.000000E+000
|RECORD=2|OwnerIndex=2021|OwnerPartId=1|FormalType=1|Electrical=4|PinConglomerate=35|PinLength=10|Location.X=580|Location.Y=530|Name=1|Designator=1|PinPropagationDelay=0.000000E+000
|RECORD=6|OwnerIndex=2021|IsNotAccesible=T|IndexInSheet=5|OwnerPartId=1|LineWidth=1|Color=16711680|LocationCount=10|X1=580|Y1=550|X2=580|Y2=546|X3=582|Y3=545|X4=578|Y4=543|X5=582|Y5=541|X6=578|Y6=539|X7=582|Y7=537|X8=578|Y8=535|X9=580|Y9=534|X10=580|Y10=530
|RECORD=41|OwnerIndex=2021|IndexInSheet=6|OwnerPartId=-1|Location.X=577|Location.Y=562|Color=8388608|FontID=1|IsHidden=T|Text=ERJ-2GEJ103X|Name=Part Number
|RECORD=41|OwnerIndex=2021|IndexInSheet=7|OwnerPartId=-1|Location.X=577|Location.Y=562|Color=8388608|FontID=1|IsHidden=T|Text=Panasonic|Name=Manufacturer
|RECORD=34|OwnerIndex=2021|IndexInSheet=-1|OwnerPartId=-1|Location.X=583|Location.Y=541|Color=8388608|FontID=1|Text=R49|Name=Designator|ReadOnlyState=1
|RECORD=41|OwnerIndex=2021|IndexInSheet=-1|OwnerPartId=-1|Location.X=583|Location.Y=531|Color=8388608|FontID=1|Text=10K_5%_0402|Name=Comment
|RECORD=44|OwnerIndex=2021
|RECORD=45|OwnerIndex=2036|IndexInSheet=-1|Description=Chip Resistor, 2-Leads, Body 1.00x0.50mm, IPC Low Density|UseComponentLibrary=T|ModelName=RESC1005X40X25ML05T05|ModelType=PCBLIB|DatafileCount=1|ModelDatafileEntity0=RESC1005X40X25ML05T05|ModelDatafileKind0=PCBLib|IsCurrent=T|DatalinksLocked=T|DatabaseDatalinksLocked=T
|RECORD=46|OwnerIndex=2037
|RECORD=48|OwnerIndex=2037
|RECORD=41|OwnerIndex=2039|IndexInSheet=-1|OwnerPartId=-1|Color=8388608|FontID=1|IsHidden=T|Text=2D|Name=Available Preview Images
|RECORD=45|OwnerIndex=2036|IndexInSheet=-1|Description=Chip Resistor, 2-Leads, Body 1.00x0.50mm, IPC Medium Density|UseComponentLibrary=T|ModelName=RESC1005X40X25NL05T05|ModelType=PCBLIB|DatafileCount=1|ModelDatafileEntity0=RESC1005X40X25NL05T05|ModelDatafileKind0=PCBLib|DatalinksLocked=T|DatabaseDatalinksLocked=T
|RECORD=46|OwnerIndex=2041
|RECORD=48|OwnerIndex=2041
|RECORD=41|OwnerIndex=2043|IndexInSheet=-1|OwnerPartId=-1|Color=8388608|FontID=1|IsHidden=T|Text=2D|Name=Available Preview Images
|RECORD=45|OwnerIndex=2036|IndexInSheet=-1|Description=Chip Resistor, 2-Leads, Body 1.00x0.50mm, IPC High Density|UseComponentLibrary=T|ModelName=RESC1005X40X25LL05T05|ModelType=PCBLIB|DatafileCount=1|ModelDatafileEntity0=RESC1005X40X25LL05T05|ModelDatafileKind0=PCBLib|DatalinksLocked=T|DatabaseDatalinksLocked=T
|RECORD=46|OwnerIndex=2045
|RECORD=48|OwnerIndex=2045
|RECORD=41|OwnerIndex=2047|IndexInSheet=-1|OwnerPartId=-1|Color=8388608|FontID=1|IsHidden=T|Text=2D|Name=Available Preview Images
|RECORD=1|LibReference=RES|PartCount=2|DisplayModeCount=2|IndexInSheet=153|OwnerPartId=-1|Location.X=570|Location.Y=470|Orientation=1|CurrentPartId=1|SourceLibraryName=Altium Content Vault|TargetFileName=*|AreaColor=11599871|Color=128|PartIDLocked=F|DesignItemId=CMP-2002-00433-1|AllPinCount=2
|RECORD=2|OwnerIndex=2049|OwnerPartId=1|OwnerPartDisplayMode=1|FormalType=1|Electrical=4|PinConglomerate=33|PinLength=10|Location.X=580|Location.Y=490|Name=2|Designator=2|PinPropagationDelay=0.000000E+000
|RECORD=2|OwnerIndex=2049|OwnerPartId=1|OwnerPartDisplayMode=1|FormalType=1|Electrical=4|PinConglomerate=35|PinLength=10|Location.X=580|Location.Y=470|Name=1|Designator=1|PinPropagationDelay=0.000000E+000
|RECORD=14|OwnerIndex=2049|IsNotAccesible=T|IndexInSheet=2|OwnerPartId=1|OwnerPartDisplayMode=1|Location.X=576|Location.Y=470|Corner.X=584|Corner.Y=490|LineWidth=1|Color=16711680|AreaColor=11599871
|RECORD=2|OwnerIndex=2049|OwnerPartId=1|FormalType=1|Electrical=4|PinConglomerate=33|PinLength=10|Location.X=580|Location.Y=490|Name=2|Designator=2|PinPropagationDelay=0.000000E+000
|RECORD=2|OwnerIndex=2049|OwnerPartId=1|FormalType=1|Electrical=4|PinConglomerate=35|PinLength=10|Location.X=580|Location.Y=470|Name=1|Designator=1|PinPropagationDelay=0.000000E+000
|RECORD=6|OwnerIndex=2049|IsNotAccesible=T|IndexInSheet=5|OwnerPartId=1|LineWidth=1|Color=16711680|LocationCount=10|X1=580|Y1=490|X2=580|Y2=486|X3=582|Y3=485|X4=578|Y4=483|X5=582|Y5=481|X6=578|Y6=479|X7=582|Y7=477|X8=578|Y8=475|X9=580|Y9=474|X10=580|Y10=470
|RECORD=41|OwnerIndex=2049|IndexInSheet=6|OwnerPartId=-1|Location.X=577|Location.Y=502|Color=8388608|FontID=1|IsHidden=T|Text=ERJ-2GEJ103X|Name=Part Number
|RECORD=41|OwnerIndex=2049|IndexInSheet=7|OwnerPartId=-1|Location.X=577|Location.Y=502|Color=8388608|FontID=1|IsHidden=T|Text=Panasonic|Name=Manufacturer
|RECORD=34|OwnerIndex=2049|IndexInSheet=-1|OwnerPartId=-1|Location.X=583|Location.Y=481|Color=8388608|FontID=1|Text=R181|Name=Designator|ReadOnlyState=1
|RECORD=41|OwnerIndex=2049|IndexInSheet=-1|OwnerPartId=-1|Location.X=583|Location.Y=471|Color=8388608|FontID=1|Text=10K_5%_0402|Name=Comment
|RECORD=44|OwnerIndex=2049
|RECORD=45|OwnerIndex=2064|IndexInSheet=-1|Description=Chip Resistor, 2-Leads, Body 1.00x0.50mm, IPC Low Density|UseComponentLibrary=T|ModelName=RESC1005X40X25ML05T05|ModelType=PCBLIB|DatafileCount=1|ModelDatafileEntity0=RESC1005X40X25ML05T05|ModelDatafileKind0=PCBLib|IsCurrent=T|DatalinksLocked=T|DatabaseDatalinksLocked=T
|RECORD=46|OwnerIndex=2065
|RECORD=48|OwnerIndex=2065
|RECORD=41|OwnerIndex=2067|IndexInSheet=-1|OwnerPartId=-1|Color=8388608|FontID=1|IsHidden=T|Text=2D|Name=Available Preview Images
|RECORD=45|OwnerIndex=2064|IndexInSheet=-1|Description=Chip Resistor, 2-Leads, Body 1.00x0.50mm, IPC Medium Density|UseComponentLibrary=T|ModelName=RESC1005X40X25NL05T05|ModelType=PCBLIB|DatafileCount=1|ModelDatafileEntity0=RESC1005X40X25NL05T05|ModelDatafileKind0=PCBLib|DatalinksLocked=T|DatabaseDatalinksLocked=T
|RECORD=46|OwnerIndex=2069
|RECORD=48|OwnerIndex=2069
|RECORD=41|OwnerIndex=2071|IndexInSheet=-1|OwnerPartId=-1|Color=8388608|FontID=1|IsHidden=T|Text=2D|Name=Available Preview Images
|RECORD=45|OwnerIndex=2064|IndexInSheet=-1|Description=Chip Resistor, 2-Leads, Body 1.00x0.50mm, IPC High Density|UseComponentLibrary=T|ModelName=RESC1005X40X25LL05T05|ModelType=PCBLIB|DatafileCount=1|ModelDatafileEntity0=RESC1005X40X25LL05T05|ModelDatafileKind0=PCBLib|DatalinksLocked=T|DatabaseDatalinksLocked=T
|RECORD=46|OwnerIndex=2073
|RECORD=48|OwnerIndex=2073
|RECORD=41|OwnerIndex=2075|IndexInSheet=-1|OwnerPartId=-1|Color=8388608|FontID=1|IsHidden=T|Text=2D|Name=Available Preview Images
|RECORD=17|IndexInSheet=154|OwnerPartId=-1|Style=4|ShowNetName=T|Location.X=580|Location.Y=460|Orientation=3|Color=128|FontID=1|Text=GND
|RECORD=17|IndexInSheet=155|OwnerPartId=-1|Style=4|ShowNetName=T|Location.X=810|Location.Y=480|Orientation=3|Color=128|FontID=1|Text=GND
|RECORD=1|LibReference=b4654b650e69147ec39a6b967a45e02|ComponentDescription=General Purpose Ceramic Capacitor, 0402, 100nF, 10%, X7R, 15%, 25V|PartCount=2|DisplayModeCount=1|IndexInSheet=156|OwnerPartId=-1|Location.X=840|Location.Y=560|CurrentPartId=1|LibraryPath=*|SourceLibraryName=Altium Content Vault|TargetFileName=*|AreaColor=11599871|Color=128|PartIDLocked=T|DesignItemId=CMP-2008-02519-2|AllPinCount=2
|RECORD=2|OwnerIndex=2079|OwnerPartId=1|Electrical=4|PinConglomerate=49|PinLength=7|Location.X=840|Location.Y=553|Name=1|Designator=1|PinPropagationDelay=0.000000E+000
|RECORD=2|OwnerIndex=2079|OwnerPartId=1|Electrical=4|PinConglomerate=51|PinLength=6|Location.X=840|Location.Y=546|Name=2|Designator=2|PinPropagationDelay=0.000000E+000
|RECORD=13|OwnerIndex=2079|IsNotAccesible=T|IndexInSheet=2|OwnerPartId=1|Location.X=850|Location.Y=553|Corner.X=830|Corner.Y=553|LineWidth=1|Color=16711680
|RECORD=13|OwnerIndex=2079|IsNotAccesible=T|IndexInSheet=3|OwnerPartId=1|Location.X=850|Location.Y=547|Corner.X=830|Corner.Y=547|LineWidth=1|Color=16711680
|RECORD=13|OwnerIndex=2079|IsNotAccesible=T|IndexInSheet=4|OwnerPartId=1|Location.X=840|Location.Y=553|Corner.X=840|Corner.Y=556|LineWidth=1|Color=16711680
|RECORD=13|OwnerIndex=2079|IsNotAccesible=T|IndexInSheet=5|OwnerPartId=1|Location.X=840|Location.Y=546|Corner.X=840|Corner.Y=545|LineWidth=1|Color=16711680
|RECORD=41|OwnerIndex=2079|IndexInSheet=6|OwnerPartId=-1|Location.X=829|Location.Y=562|Color=8388608|FontID=1|IsHidden=T|Text=1|Name=Package Quantity
|RECORD=41|OwnerIndex=2079|IndexInSheet=7|OwnerPartId=-1|Location.X=829|Location.Y=562|Color=8388608|FontID=1|IsHidden=T|Text=100nF|Name=Capacitance
|RECORD=41|OwnerIndex=2079|IndexInSheet=8|OwnerPartId=-1|Location.X=829|Location.Y=562|Color=8388608|FontID=1|IsHidden=T|Text=-55°C|Name=Min Operating Temperature
|RECORD=41|OwnerIndex=2079|IndexInSheet=9|OwnerPartId=-1|Location.X=829|Location.Y=562|Color=8388608|FontID=1|IsHidden=T|Text=25V|Name=Voltage
|RECORD=41|OwnerIndex=2079|IndexInSheet=10|OwnerPartId=-1|Location.X=829|Location.Y=562|Color=8388608|FontID=1|IsHidden=T|Text=25V|Name=Voltage Rating
|RECORD=41|OwnerIndex=2079|IndexInSheet=11|OwnerPartId=-1|Location.X=829|Location.Y=562|Color=8388608|FontID=1|IsHidden=T|Text=Flat|Name=Construction
|RECORD=41|OwnerIndex=2079|IndexInSheet=12|OwnerPartId=-1|Location.X=829|Location.Y=562|Color=8388608|FontID=1|IsHidden=T|Text=125°C|Name=Max Operating Temperature
|RECORD=41|OwnerIndex=2079|IndexInSheet=13|OwnerPartId=-1|Location.X=829|Location.Y=562|Color=8388608|FontID=1|IsHidden=T|Text=No|Name=Radiation Hardening
|RECORD=41|OwnerIndex=2079|IndexInSheet=14|OwnerPartId=-1|Location.X=829|Location.Y=562|Color=8388608|FontID=1|IsHidden=T|Text=0.5mm|Name=Depth
|RECORD=41|OwnerIndex=2079|IndexInSheet=15|OwnerPartId=-1|Location.X=829|Location.Y=562|Color=8388608|FontID=1|IsHidden=T|Text=0.022inch|Name=Thickness
|RECORD=41|OwnerIndex=2079|IndexInSheet=16|OwnerPartId=-1|Location.X=829|Location.Y=562|Color=8388608|FontID=1|IsHidden=T|Text=25V|Name=Voltage Rating (DC)
|RECORD=41|OwnerIndex=2079|IndexInSheet=17|OwnerPartId=-1|Location.X=829|Location.Y=562|Color=8388608|FontID=1|IsHidden=T|Text=2|Name=Number of Pins
|RECORD=41|OwnerIndex=2079|IndexInSheet=18|OwnerPartId=-1|Location.X=829|Location.Y=562|Color=8388608|FontID=1|IsHidden=T|Text=Lead Free|Name=Lead Free
|RECORD=41|OwnerIndex=2079|IndexInSheet=19|OwnerPartId=-1|Location.X=829|Location.Y=562|Color=8388608|FontID=1|IsHidden=T|Text=-|Name=Series
|RECORD=41|OwnerIndex=2079|IndexInSheet=20|OwnerPartId=-1|Location.X=829|Location.Y=562|Color=8388608|FontID=1|IsHidden=T|Text=No SVHC|Name=REACH SVHC
|RECORD=41|OwnerIndex=2079|IndexInSheet=21|OwnerPartId=-1|Location.X=829|Location.Y=562|Color=8388608|FontID=1|IsHidden=T|Text=1mm|Name=Length
|RECORD=41|OwnerIndex=2079|IndexInSheet=22|OwnerPartId=-1|Location.X=829|Location.Y=562|Color=8388608|FontID=1|IsHidden=T|Text=X7R|Name=Dielectric
|RECORD=41|OwnerIndex=2079|IndexInSheet=23|OwnerPartId=-1|Location.X=829|Location.Y=562|Color=8388608|FontID=1|IsHidden=T|Text=Yes|Name=RoHS Compliant
|RECORD=41|OwnerIndex=2079|IndexInSheet=24|OwnerPartId=-1|Location.X=829|Location.Y=562|Color=8388608|FontID=1|IsHidden=T|Text=Surface Mount|Name=Mount
|RECORD=41|OwnerIndex=2079|IndexInSheet=25|OwnerPartId=-1|Location.X=829|Location.Y=562|Color=8388608|FontID=1|IsHidden=T|Text=Tape and Reel|Name=Packaging
|RECORD=41|OwnerIndex=2079|IndexInSheet=26|OwnerPartId=-1|Location.X=829|Location.Y=562|Color=8388608|FontID=1|IsHidden=T|Text=0402|Name=Case/Package
|RECORD=41|OwnerIndex=2079|IndexInSheet=27|OwnerPartId=-1|Location.X=829|Location.Y=562|Color=8388608|FontID=1|IsHidden=T|Text=0402|Name=Case Code (Imperial)
|RECORD=41|OwnerIndex=2079|IndexInSheet=28|OwnerPartId=-1|Location.X=829|Location.Y=562|Color=8388608|FontID=1|IsHidden=T|Text=SMD/SMT|Name=Termination
|RECORD=41|OwnerIndex=2079|IndexInSheet=29|OwnerPartId=-1|Location.X=829|Location.Y=562|Color=8388608|FontID=1|IsHidden=T|Text=0.02inch|Name=Width
|RECORD=41|OwnerIndex=2079|IndexInSheet=30|OwnerPartId=-1|Location.X=829|Location.Y=562|Color=8388608|FontID=1|IsHidden=T|Text=1005|Name=Case Code (Metric)
|RECORD=41|OwnerIndex=2079|IndexInSheet=31|OwnerPartId=-1|Location.X=829|Location.Y=562|Color=8388608|FontID=1|IsHidden=T|Text=10%|Name=Tolerance
|RECORD=34|OwnerIndex=2079|IndexInSheet=-1|OwnerPartId=-1|Location.X=830|Location.Y=540|Orientation=1|Color=8388608|FontID=2|Text=C110|Name=Designator|ReadOnlyState=1
|RECORD=41|OwnerIndex=2079|IndexInSheet=-1|OwnerPartId=1|Location.X=860|Location.Y=525|Orientation=1|Color=8388608|FontID=2|Text=0.1uF_25V_0402|Name=Comment
|RECORD=44|OwnerIndex=2079
|RECORD=45|OwnerIndex=2116|IndexInSheet=-1|UseComponentLibrary=T|ModelName=FP-0402-L_1_0_1-W_0_5_0_1-IPC_C|ModelType=PCBLIB|DatafileCount=1|ModelDatafileEntity0=FP-0402-L_1_0_1-W_0_5_0_1-IPC_C|ModelDatafileKind0=PCBLib|IsCurrent=T|DatalinksLocked=T|DatabaseDatalinksLocked=T
|RECORD=46|OwnerIndex=2117
|RECORD=48|OwnerIndex=2117
|RECORD=45|OwnerIndex=2116|IndexInSheet=-1|UseComponentLibrary=T|ModelName=FP-0402-L_1_0_1-W_0_5_0_1-IPC_B|ModelType=PCBLIB|DatafileCount=1|ModelDatafileEntity0=FP-0402-L_1_0_1-W_0_5_0_1-IPC_B|ModelDatafileKind0=PCBLib|DatalinksLocked=T|DatabaseDatalinksLocked=T
|RECORD=46|OwnerIndex=2120
|RECORD=48|OwnerIndex=2120
|RECORD=45|OwnerIndex=2116|IndexInSheet=-1|UseComponentLibrary=T|ModelName=FP-0402-L_1_0_1-W_0_5_0_1-MFG|ModelType=PCBLIB|DatafileCount=1|ModelDatafileEntity0=FP-0402-L_1_0_1-W_0_5_0_1-MFG|ModelDatafileKind0=PCBLib|DatalinksLocked=T|DatabaseDatalinksLocked=T
|RECORD=46|OwnerIndex=2123
|RECORD=48|OwnerIndex=2123
|RECORD=45|OwnerIndex=2116|IndexInSheet=-1|UseComponentLibrary=T|ModelName=FP-0402-L_1_0_1-W_0_5_0_1-IPC_A|ModelType=PCBLIB|DatafileCount=1|ModelDatafileEntity0=FP-0402-L_1_0_1-W_0_5_0_1-IPC_A|ModelDatafileKind0=PCBLib|DatalinksLocked=T|DatabaseDatalinksLocked=T
|RECORD=46|OwnerIndex=2126
|RECORD=48|OwnerIndex=2126
|RECORD=17|IndexInSheet=157|OwnerPartId=-1|ShowNetName=T|Location.X=890|Location.Y=580|Orientation=1|Color=128|FontID=1|Text=GNSS2_P3V3
|RECORD=27|IndexInSheet=158|OwnerPartId=-1|LineWidth=1|Color=8388608|LocationCount=2|X1=460|Y1=820|X2=570|Y2=820
|RECORD=27|IndexInSheet=159|OwnerPartId=-1|LineWidth=1|Color=8388608|LocationCount=2|X1=460|Y1=810|X2=570|Y2=810
|RECORD=27|IndexInSheet=160|OwnerPartId=-1|LineWidth=1|Color=8388608|LocationCount=3|X1=570|Y1=840|X2=550|Y2=840|X3=550|Y3=770
|RECORD=27|IndexInSheet=161|OwnerPartId=-1|LineWidth=1|Color=8388608|LocationCount=2|X1=740|Y1=770|X2=750|Y2=770
|RECORD=27|IndexInSheet=162|OwnerPartId=-1|LineWidth=1|Color=8388608|LocationCount=3|X1=420|Y1=790|X2=400|Y2=790|X3=400|Y3=850
|RECORD=27|IndexInSheet=163|OwnerPartId=-1|LineWidth=1|Color=8388608|LocationCount=2|X1=740|Y1=840|X2=770|Y2=840
|RECORD=27|IndexInSheet=164|OwnerPartId=-1|LineWidth=1|Color=8388608|LocationCount=2|X1=770|Y1=850|X2=740|Y2=850
|RECORD=27|IndexInSheet=165|OwnerPartId=-1|LineWidth=1|Color=8388608|LocationCount=2|X1=810|Y1=850|X2=870|Y2=850
|RECORD=27|IndexInSheet=166|OwnerPartId=-1|LineWidth=1|Color=8388608|LocationCount=2|X1=810|Y1=840|X2=870|Y2=840
|RECORD=27|IndexInSheet=167|OwnerPartId=-1|LineWidth=1|Color=8388608|LocationCount=3|X1=240|Y1=850|X2=240|Y2=770|X3=220|Y3=770
|RECORD=27|IndexInSheet=168|OwnerPartId=-1|LineWidth=1|Color=8388608|LocationCount=2|X1=260|Y1=740|X2=260|Y2=720
|RECORD=27|IndexInSheet=169|OwnerPartId=-1|LineWidth=1|Color=8388608|LocationCount=2|X1=260|Y1=810|X2=260|Y2=770
|RECORD=27|IndexInSheet=170|OwnerPartId=-1|LineWidth=1|Color=8388608|LocationCount=2|X1=300|Y1=740|X2=300|Y2=720
|RECORD=27|IndexInSheet=171|OwnerPartId=-1|LineWidth=1|Color=8388608|LocationCount=2|X1=300|Y1=830|X2=300|Y2=770
|RECORD=27|IndexInSheet=172|OwnerPartId=-1|LineWidth=1|Color=8388608|LocationCount=2|X1=340|Y1=770|X2=340|Y2=850
|RECORD=27|IndexInSheet=173|OwnerPartId=-1|LineWidth=1|Color=8388608|LocationCount=2|X1=380|Y1=770|X2=380|Y2=850
|RECORD=27|IndexInSheet=174|OwnerPartId=-1|LineWidth=1|Color=8388608|LocationCount=3|X1=380|Y1=750|X2=380|Y2=720|X3=340|Y3=720
|RECORD=27|IndexInSheet=175|OwnerPartId=-1|LineWidth=1|Color=8388608|LocationCount=3|X1=590|Y1=720|X2=590|Y2=750|X3=550|Y3=750
|RECORD=27|IndexInSheet=176|OwnerPartId=-1|LineWidth=1|Color=8388608|LocationCount=3|X1=590|Y1=700|X2=590|Y2=680|X3=550|Y3=680
|RECORD=27|IndexInSheet=177|OwnerPartId=-1|LineWidth=1|Color=8388608|LocationCount=4|X1=450|Y1=720|X2=450|Y2=690|X3=490|Y3=690|X4=490|Y4=660
|RECORD=27|IndexInSheet=178|OwnerPartId=-1|LineWidth=1|Color=8388608|LocationCount=5|X1=220|Y1=720|X2=260|Y2=720|X3=300|Y3=720|X4=340|Y4=720|X5=340|Y5=750
|RECORD=27|IndexInSheet=179|OwnerPartId=-1|LineWidth=1|Color=8388608|LocationCount=5|X1=300|Y1=850|X2=340|Y2=850|X3=380|Y3=850|X4=400|Y4=850|X5=570|Y5=850
|RECORD=27|IndexInSheet=180|OwnerPartId=-1|LineWidth=1|Color=8388608|LocationCount=3|X1=460|Y1=790|X2=490|Y2=790|X3=570|Y3=790
|RECORD=27|IndexInSheet=181|OwnerPartId=-1|LineWidth=1|Color=8388608|LocationCount=4|X1=550|Y1=720|X2=550|Y2=750|X3=550|Y3=770|X4=570|Y4=770
|RECORD=27|IndexInSheet=182|OwnerPartId=-1|LineWidth=1|Color=8388608|LocationCount=4|X1=740|Y1=780|X2=750|Y2=780|X3=750|Y3=770|X4=750|Y4=750
|RECORD=27|IndexInSheet=183|OwnerPartId=-1|LineWidth=1|Color=8388608|LocationCount=3|X1=550|Y1=660|X2=550|Y2=680|X3=550|Y3=700
|RECORD=27|IndexInSheet=184|OwnerPartId=-1|LineWidth=1|Color=8388608|LocationCount=2|X1=1210|Y1=160|X2=1190|Y2=160
|RECORD=27|IndexInSheet=185|OwnerPartId=-1|LineWidth=1|Color=8388608|LocationCount=4|X1=1150|Y1=370|X2=1180|Y2=370|X3=1180|Y3=310|X4=1210|Y4=310
|RECORD=27|IndexInSheet=186|OwnerPartId=-1|LineWidth=1|Color=8388608|LocationCount=2|X1=1150|Y1=310|X2=1150|Y2=320
|RECORD=27|IndexInSheet=187|OwnerPartId=-1|LineWidth=1|Color=8388608|LocationCount=3|X1=1210|Y1=200|X2=1190|Y2=200|X3=1190|Y3=210
|RECORD=27|IndexInSheet=188|OwnerPartId=-1|LineWidth=1|Color=8388608|LocationCount=3|X1=1350|Y1=160|X2=1360|Y2=160|X3=1360|Y3=150
|RECORD=27|IndexInSheet=189|OwnerPartId=-1|LineWidth=1|Color=8388608|LocationCount=2|X1=1110|Y1=290|X2=1210|Y2=290
|RECORD=27|IndexInSheet=190|OwnerPartId=-1|LineWidth=1|Color=8388608|LocationCount=2|X1=1110|Y1=250|X2=1210|Y2=250
|RECORD=27|IndexInSheet=191|OwnerPartId=-1|LineWidth=1|Color=8388608|LocationCount=2|X1=1070|Y1=250|X2=1030|Y2=250
|RECORD=27|IndexInSheet=192|OwnerPartId=-1|LineWidth=1|Color=8388608|LocationCount=2|X1=1030|Y1=290|X2=1070|Y2=290
|RECORD=27|IndexInSheet=193|OwnerPartId=-1|LineWidth=1|Color=8388608|LocationCount=2|X1=1030|Y1=230|X2=1070|Y2=230
|RECORD=27|IndexInSheet=194|OwnerPartId=-1|LineWidth=1|Color=8388608|LocationCount=2|X1=1110|Y1=230|X2=1210|Y2=230
|RECORD=27|IndexInSheet=195|OwnerPartId=-1|LineWidth=1|Color=8388608|LocationCount=2|X1=1110|Y1=270|X2=1210|Y2=270
|RECORD=27|IndexInSheet=196|OwnerPartId=-1|LineWidth=1|Color=8388608|LocationCount=2|X1=1070|Y1=270|X2=1030|Y2=270
|RECORD=27|IndexInSheet=197|OwnerPartId=-1|LineWidth=1|Color=8388608|LocationCount=2|X1=1200|Y1=640|X2=1180|Y2=640
|RECORD=27|IndexInSheet=198|OwnerPartId=-1|LineWidth=1|Color=8388608|LocationCount=4|X1=1140|Y1=850|X2=1170|Y2=850|X3=1170|Y3=790|X4=1200|Y4=790
|RECORD=27|IndexInSheet=199|OwnerPartId=-1|LineWidth=1|Color=8388608|LocationCount=2|X1=1140|Y1=790|X2=1140|Y2=800
|RECORD=27|IndexInSheet=200|OwnerPartId=-1|LineWidth=1|Color=8388608|LocationCount=3|X1=1200|Y1=680|X2=1180|Y2=680|X3=1180|Y3=690
|RECORD=27|IndexInSheet=201|OwnerPartId=-1|LineWidth=1|Color=8388608|LocationCount=3|X1=1340|Y1=640|X2=1350|Y2=640|X3=1350|Y3=630
|RECORD=27|IndexInSheet=202|OwnerPartId=-1|LineWidth=1|Color=8388608|LocationCount=2|X1=1100|Y1=770|X2=1200|Y2=770
|RECORD=27|IndexInSheet=203|OwnerPartId=-1|LineWidth=1|Color=8388608|LocationCount=2|X1=1100|Y1=730|X2=1200|Y2=730
|RECORD=27|IndexInSheet=204|OwnerPartId=-1|LineWidth=1|Color=8388608|LocationCount=2|X1=1100|Y1=710|X2=1200|Y2=710
|RECORD=27|IndexInSheet=205|OwnerPartId=-1|LineWidth=1|Color=8388608|LocationCount=2|X1=1100|Y1=750|X2=1200|Y2=750
|RECORD=27|IndexInSheet=206|OwnerPartId=-1|LineWidth=1|Color=8388608|LocationCount=2|X1=990|Y1=770|X2=1060|Y2=770
|RECORD=27|IndexInSheet=207|OwnerPartId=-1|LineWidth=1|Color=8388608|LocationCount=2|X1=1060|Y1=730|X2=990|Y2=730
|RECORD=27|IndexInSheet=208|OwnerPartId=-1|LineWidth=1|Color=8388608|LocationCount=2|X1=1020|Y1=750|X2=1060|Y2=750
|RECORD=27|IndexInSheet=209|OwnerPartId=-1|LineWidth=1|Color=8388608|LocationCount=2|X1=1060|Y1=710|X2=1020|Y2=710
|RECORD=27|IndexInSheet=210|OwnerPartId=-1|LineWidth=1|Color=8388608|LocationCount=2|X1=450|Y1=150|X2=430|Y2=150
|RECORD=27|IndexInSheet=211|OwnerPartId=-1|LineWidth=1|Color=8388608|LocationCount=4|X1=390|Y1=360|X2=420|Y2=360|X3=420|Y3=300|X4=450|Y4=300
|RECORD=27|IndexInSheet=212|OwnerPartId=-1|LineWidth=1|Color=8388608|LocationCount=2|X1=390|Y1=300|X2=390|Y2=310
|RECORD=27|IndexInSheet=213|OwnerPartId=-1|LineWidth=1|Color=8388608|LocationCount=3|X1=450|Y1=190|X2=430|Y2=190|X3=430|Y3=200
|RECORD=27|IndexInSheet=214|OwnerPartId=-1|LineWidth=1|Color=8388608|LocationCount=3|X1=590|Y1=150|X2=600|Y2=150|X3=600|Y3=140
|RECORD=27|IndexInSheet=215|OwnerPartId=-1|LineWidth=1|Color=8388608|LocationCount=2|X1=330|Y1=280|X2=450|Y2=280
|RECORD=27|IndexInSheet=216|OwnerPartId=-1|LineWidth=1|Color=8388608|LocationCount=2|X1=290|Y1=280|X2=260|Y2=280
|RECORD=27|IndexInSheet=217|OwnerPartId=-1|LineWidth=1|Color=8388608|LocationCount=2|X1=330|Y1=260|X2=450|Y2=260
|RECORD=27|IndexInSheet=218|OwnerPartId=-1|LineWidth=1|Color=8388608|LocationCount=2|X1=290|Y1=260|X2=260|Y2=260
|RECORD=27|IndexInSheet=219|OwnerPartId=-1|LineWidth=1|Color=8388608|LocationCount=2|X1=330|Y1=220|X2=450|Y2=220
|RECORD=27|IndexInSheet=220|OwnerPartId=-1|LineWidth=1|Color=8388608|LocationCount=2|X1=450|Y1=240|X2=330|Y2=240
|RECORD=27|IndexInSheet=221|OwnerPartId=-1|LineWidth=1|Color=8388608|LocationCount=2|X1=260|Y1=240|X2=290|Y2=240
|RECORD=27|IndexInSheet=222|OwnerPartId=-1|LineWidth=1|Color=8388608|LocationCount=2|X1=260|Y1=220|X2=290|Y2=220
|RECORD=27|IndexInSheet=223|OwnerPartId=-1|LineWidth=1|Color=8388608|LocationCount=3|X1=1340|Y1=350|X2=1390|Y2=350|X3=1390|Y3=250
|RECORD=27|IndexInSheet=224|OwnerPartId=-1|LineWidth=1|Color=8388608|LocationCount=3|X1=1340|Y1=380|X2=1370|Y2=380|X3=1370|Y3=290
|RECORD=27|IndexInSheet=225|OwnerPartId=-1|LineWidth=1|Color=8388608|LocationCount=2|X1=1280|Y1=380|X2=1300|Y2=380
|RECORD=27|IndexInSheet=226|OwnerPartId=-1|LineWidth=1|Color=8388608|LocationCount=2|X1=1280|Y1=350|X2=1300|Y2=350
|RECORD=27|IndexInSheet=227|OwnerPartId=-1|LineWidth=1|Color=8388608|LocationCount=3|X1=1320|Y1=900|X2=1360|Y2=900|X3=1360|Y3=770
|RECORD=27|IndexInSheet=228|OwnerPartId=-1|LineWidth=1|Color=8388608|LocationCount=3|X1=1320|Y1=880|X2=1370|Y2=880|X3=1370|Y3=730
|RECORD=27|IndexInSheet=229|OwnerPartId=-1|LineWidth=1|Color=8388608|LocationCount=2|X1=1280|Y1=880|X2=1250|Y2=880
|RECORD=27|IndexInSheet=230|OwnerPartId=-1|LineWidth=1|Color=8388608|LocationCount=2|X1=1280|Y1=900|X2=1250|Y2=900
|RECORD=27|IndexInSheet=231|OwnerPartId=-1|LineWidth=1|Color=8388608|LocationCount=2|X1=710|Y1=320|X2=790|Y2=320
|RECORD=27|IndexInSheet=232|OwnerPartId=-1|LineWidth=1|Color=8388608|LocationCount=2|X1=790|Y1=330|X2=710|Y2=330
|RECORD=27|IndexInSheet=233|OwnerPartId=-1|LineWidth=1|Color=8388608|LocationCount=2|X1=710|Y1=340|X2=790|Y2=340
|RECORD=27|IndexInSheet=234|OwnerPartId=-1|LineWidth=1|Color=8388608|LocationCount=2|X1=790|Y1=350|X2=710|Y2=350
|RECORD=27|IndexInSheet=235|OwnerPartId=-1|LineWidth=1|Color=8388608|LocationCount=2|X1=670|Y1=340|X2=600|Y2=340
|RECORD=27|IndexInSheet=236|OwnerPartId=-1|LineWidth=1|Color=8388608|LocationCount=2|X1=670|Y1=320|X2=630|Y2=320
|RECORD=27|IndexInSheet=237|OwnerPartId=-1|LineWidth=1|Color=8388608|LocationCount=4|X1=490|Y1=760|X2=490|Y2=770|X3=450|Y3=770|X4=450|Y4=740
|RECORD=27|IndexInSheet=238|OwnerPartId=-1|LineWidth=1|Color=8388608|LocationCount=2|X1=490|Y1=770|X2=490|Y2=790
|RECORD=27|IndexInSheet=239|OwnerPartId=-1|LineWidth=1|Color=8388608|LocationCount=3|X1=1090|Y1=690|X2=1180|Y2=690|X3=1200|Y3=690
|RECORD=27|IndexInSheet=240|OwnerPartId=-1|LineWidth=1|Color=8388608|LocationCount=4|X1=1200|Y1=660|X2=1180|Y2=660|X3=1180|Y3=640|X4=1180|Y4=630
|RECORD=27|IndexInSheet=241|OwnerPartId=-1|LineWidth=1|Color=8388608|LocationCount=3|X1=1340|Y1=730|X2=1370|Y2=730|X3=1390|Y3=730
|RECORD=27|IndexInSheet=242|OwnerPartId=-1|LineWidth=1|Color=8388608|LocationCount=3|X1=1390|Y1=770|X2=1360|Y2=770|X3=1340|Y3=770
|RECORD=27|IndexInSheet=243|OwnerPartId=-1|LineWidth=1|Color=8388608|LocationCount=3|X1=1140|Y1=820|X2=1140|Y2=850|X3=1140|Y3=870
|RECORD=27|IndexInSheet=244|OwnerPartId=-1|LineWidth=1|Color=8388608|LocationCount=3|X1=340|Y1=200|X2=430|Y2=200|X3=450|Y3=200
|RECORD=27|IndexInSheet=245|OwnerPartId=-1|LineWidth=1|Color=8388608|LocationCount=4|X1=450|Y1=170|X2=430|Y2=170|X3=430|Y3=150|X4=430|Y4=140
|RECORD=27|IndexInSheet=246|OwnerPartId=-1|LineWidth=1|Color=8388608|LocationCount=3|X1=590|Y1=240|X2=630|Y2=240|X3=660|Y3=240
|RECORD=27|IndexInSheet=247|OwnerPartId=-1|LineWidth=1|Color=8388608|LocationCount=3|X1=590|Y1=280|X2=600|Y2=280|X3=660|Y3=280
|RECORD=27|IndexInSheet=248|OwnerPartId=-1|LineWidth=1|Color=8388608|LocationCount=4|X1=670|Y1=350|X2=600|Y2=350|X3=600|Y3=340|X4=600|Y4=280
|RECORD=27|IndexInSheet=249|OwnerPartId=-1|LineWidth=1|Color=8388608|LocationCount=4|X1=670|Y1=330|X2=630|Y2=330|X3=630|Y3=320|X4=630|Y4=240
|RECORD=27|IndexInSheet=250|OwnerPartId=-1|LineWidth=1|Color=8388608|LocationCount=3|X1=390|Y1=330|X2=390|Y2=360|X3=390|Y3=380
|RECORD=27|IndexInSheet=251|OwnerPartId=-1|LineWidth=1|Color=8388608|LocationCount=4|X1=120|Y1=790|X2=180|Y2=790|X3=180|Y3=780|X4=180|Y4=770
|RECORD=27|IndexInSheet=252|OwnerPartId=-1|LineWidth=1|Color=8388608|LocationCount=2|X1=120|Y1=780|X2=180|Y2=780
|RECORD=27|IndexInSheet=253|OwnerPartId=-1|LineWidth=1|Color=8388608|LocationCount=5|X1=120|Y1=770|X2=180|Y2=770|X3=180|Y3=760|X4=180|Y4=750|X5=180|Y5=740
|RECORD=27|IndexInSheet=254|OwnerPartId=-1|LineWidth=1|Color=8388608|LocationCount=2|X1=120|Y1=760|X2=180|Y2=760
|RECORD=27|IndexInSheet=255|OwnerPartId=-1|LineWidth=1|Color=8388608|LocationCount=2|X1=120|Y1=750|X2=180|Y2=750
|RECORD=27|IndexInSheet=256|OwnerPartId=-1|LineWidth=1|Color=8388608|LocationCount=2|X1=120|Y1=730|X2=180|Y2=730
|RECORD=27|IndexInSheet=257|OwnerPartId=-1|LineWidth=1|Color=8388608|LocationCount=6|X1=120|Y1=740|X2=180|Y2=740|X3=180|Y3=730|X4=180|Y4=720|X5=220|Y5=720|X6=220|Y6=750
|RECORD=27|IndexInSheet=258|OwnerPartId=-1|LineWidth=1|Color=8388608|LocationCount=2|X1=180|Y1=690|X2=180|Y2=720
|RECORD=27|IndexInSheet=259|OwnerPartId=-1|LineWidth=1|Color=8388608|LocationCount=3|X1=120|Y1=810|X2=260|Y2=810|X3=420|Y3=810
|RECORD=27|IndexInSheet=260|OwnerPartId=-1|LineWidth=1|Color=8388608|LocationCount=7|X1=120|Y1=820|X2=150|Y2=820|X3=150|Y3=830|X4=300|Y4=830|X5=390|Y5=830|X6=390|Y6=820|X7=420|Y7=820
|RECORD=27|IndexInSheet=261|OwnerPartId=-1|LineWidth=1|Color=8388608|LocationCount=5|X1=120|Y1=830|X2=140|Y2=830|X3=140|Y3=850|X4=240|Y4=850|X5=250|Y5=850
|RECORD=27|IndexInSheet=262|OwnerPartId=-1|LineWidth=1|Color=8388608|LocationCount=2|X1=400|Y1=850|X2=400|Y2=870
|RECORD=27|IndexInSheet=263|OwnerPartId=-1|LineWidth=1|Color=8388608|LocationCount=4|X1=190|Y1=530|X2=170|Y2=530|X3=170|Y3=550|X4=190|Y4=550
|RECORD=27|IndexInSheet=264|OwnerPartId=-1|LineWidth=1|Color=8388608|LocationCount=2|X1=300|Y1=480|X2=310|Y2=480
|RECORD=27|IndexInSheet=265|OwnerPartId=-1|LineWidth=1|Color=8388608|LocationCount=2|X1=70|Y1=520|X2=70|Y2=550
|RECORD=27|IndexInSheet=266|OwnerPartId=-1|LineWidth=1|Color=8388608|LocationCount=2|X1=110|Y1=520|X2=110|Y2=550
|RECORD=27|IndexInSheet=267|OwnerPartId=-1|LineWidth=1|Color=8388608|LocationCount=3|X1=110|Y1=500|X2=110|Y2=480|X3=70|Y3=480
|RECORD=27|IndexInSheet=268|OwnerPartId=-1|LineWidth=1|Color=8388608|LocationCount=3|X1=390|Y1=550|X2=430|Y2=550|X3=430|Y3=540
|RECORD=27|IndexInSheet=269|OwnerPartId=-1|LineWidth=1|Color=8388608|LocationCount=3|X1=430|Y1=520|X2=430|Y2=500|X3=390|Y3=500
|RECORD=27|IndexInSheet=270|OwnerPartId=-1|LineWidth=1|Color=8388608|LocationCount=2|X1=430|Y1=550|X2=430|Y2=580
|RECORD=27|IndexInSheet=271|OwnerPartId=-1|LineWidth=1|Color=8388608|LocationCount=3|X1=300|Y1=530|X2=340|Y2=530|X3=340|Y3=550
|RECORD=27|IndexInSheet=272|OwnerPartId=-1|LineWidth=1|Color=8388608|LocationCount=3|X1=660|Y1=560|X2=650|Y2=560|X3=650|Y3=580
|RECORD=27|IndexInSheet=273|OwnerPartId=-1|LineWidth=1|Color=8388608|LocationCount=3|X1=660|Y1=540|X2=630|Y2=540|X3=630|Y3=570
|RECORD=27|IndexInSheet=274|OwnerPartId=-1|LineWidth=1|Color=8388608|LocationCount=3|X1=800|Y1=500|X2=810|Y2=500|X3=810|Y3=480
|RECORD=27|IndexInSheet=275|OwnerPartId=-1|LineWidth=1|Color=8388608|LocationCount=2|X1=800|Y1=570|X2=810|Y2=570
|RECORD=27|IndexInSheet=276|OwnerPartId=-1|LineWidth=1|Color=8388608|LocationCount=3|X1=840|Y1=540|X2=840|Y2=500|X3=810|Y3=500
|RECORD=27|IndexInSheet=277|OwnerPartId=-1|LineWidth=1|Color=8388608|LocationCount=2|X1=840|Y1=560|X2=840|Y2=570
|RECORD=27|IndexInSheet=278|OwnerPartId=-1|LineWidth=1|Color=8388608|LocationCount=5|X1=580|Y1=500|X2=580|Y2=510|X3=620|Y3=510|X4=620|Y4=530|X5=660|Y5=530
|RECORD=27|IndexInSheet=279|OwnerPartId=-1|LineWidth=1|Color=8388608|LocationCount=2|X1=580|Y1=520|X2=580|Y2=510
|RECORD=27|IndexInSheet=280|OwnerPartId=-1|LineWidth=1|Color=8388608|LocationCount=4|X1=580|Y1=560|X2=580|Y2=570|X3=600|Y3=570|X4=600|Y4=580
|RECORD=27|IndexInSheet=281|OwnerPartId=-1|LineWidth=1|Color=8388608|LocationCount=5|X1=60|Y1=580|X2=60|Y2=550|X3=70|Y3=550|X4=110|Y4=550|X5=170|Y5=550
|RECORD=27|IndexInSheet=282|OwnerPartId=-1|LineWidth=1|Color=8388608|LocationCount=4|X1=300|Y1=490|X2=310|Y2=490|X3=310|Y3=480|X4=310|Y4=470
|RECORD=27|IndexInSheet=283|OwnerPartId=-1|LineWidth=1|Color=8388608|LocationCount=4|X1=300|Y1=550|X2=340|Y2=550|X3=390|Y3=550|X4=390|Y4=540
|RECORD=27|IndexInSheet=284|OwnerPartId=-1|LineWidth=1|Color=8388608|LocationCount=3|X1=70|Y1=500|X2=70|Y2=480|X3=70|Y3=470
|RECORD=27|IndexInSheet=285|OwnerPartId=-1|LineWidth=1|Color=8388608|LocationCount=3|X1=390|Y1=520|X2=390|Y2=500|X3=390|Y3=490
|RECORD=27|IndexInSheet=286|OwnerPartId=-1|LineWidth=1|Color=8388608|LocationCount=3|X1=1100|Y1=210|X2=1190|Y2=210|X3=1210|Y3=210
|RECORD=27|IndexInSheet=287|OwnerPartId=-1|LineWidth=1|Color=8388608|LocationCount=4|X1=1210|Y1=180|X2=1190|Y2=180|X3=1190|Y3=160|X4=1190|Y4=150
|RECORD=27|IndexInSheet=288|OwnerPartId=-1|LineWidth=1|Color=8388608|LocationCount=3|X1=1420|Y1=250|X2=1390|Y2=250|X3=1350|Y3=250
|RECORD=27|IndexInSheet=289|OwnerPartId=-1|LineWidth=1|Color=8388608|LocationCount=3|X1=1420|Y1=290|X2=1370|Y2=290|X3=1350|Y3=290
|RECORD=27|IndexInSheet=290|OwnerPartId=-1|LineWidth=1|Color=8388608|LocationCount=3|X1=1150|Y1=340|X2=1150|Y2=370|X3=1150|Y3=390
|RECORD=27|IndexInSheet=291|OwnerPartId=-1|LineWidth=1|Color=8388608|LocationCount=3|X1=600|Y1=570|X2=630|Y2=570|X3=660|Y3=570
|RECORD=27|IndexInSheet=292|OwnerPartId=-1|LineWidth=1|Color=8388608|LocationCount=6|X1=800|Y1=560|X2=810|Y2=560|X3=810|Y3=570|X4=840|Y4=570|X5=890|Y5=570|X6=890|Y6=580
|RECORD=1|LibReference=IC_TPS2116DRLR|ComponentDescription=1.6-V to 5.5-V, 40-m?, 2.5-A, low-IQ, priority power multiplexer 8-SOT-5X3 -40 to 125|PartCount=2|DisplayModeCount=1|IndexInSheet=293|OwnerPartId=-1|Location.X=1110|Location.Y=510|CurrentPartId=1|LibraryPath=*|SourceLibraryName=LotusSound.IntLib|TargetFileName=*|AreaColor=11599871|Color=128|PartIDLocked=T|DesignItemId=IC_TPS2116DRLR|AllPinCount=8
|RECORD=41|OwnerIndex=2265|OwnerPartId=-1|Location.X=1110|Location.Y=510|Color=8388608|FontID=3|IsHidden=T|Text=https://www.snapeda.com/parts/TPS2116DRLR/Texas%20Instruments/view-part/5674360/?ref=eda|Name=Check_prices
|RECORD=41|OwnerIndex=2265|IndexInSheet=1|OwnerPartId=-1|Location.X=1110|Location.Y=510|Color=8388608|FontID=1|IsHidden=T|Text=TPS2116DRLR|Name=MP
|RECORD=41|OwnerIndex=2265|IndexInSheet=2|OwnerPartId=-1|Location.X=1110|Location.Y=510|Color=8388608|FontID=1|IsHidden=T|Text=Package|Name=Package
|RECORD=41|OwnerIndex=2265|IndexInSheet=3|OwnerPartId=-1|Location.X=1110|Location.Y=510|Color=8388608|FontID=1|IsHidden=T|Text=None|Name=Price
|RECORD=41|OwnerIndex=2265|IndexInSheet=4|OwnerPartId=-1|Location.X=1110|Location.Y=510|Color=8388608|FontID=1|IsHidden=T|Text=No availability data|Name=Availability
|RECORD=41|OwnerIndex=2265|IndexInSheet=5|OwnerPartId=-1|Location.X=1110|Location.Y=510|Color=8388608|FontID=1|IsHidden=T|Text=Texas Instruments|Name=MF
|RECORD=41|OwnerIndex=2265|IndexInSheet=6|OwnerPartId=-1|Location.X=1110|Location.Y=510|Color=8388608|FontID=3|IsHidden=T|Text=https://www.snapeda.com/parts/TPS2116DRLR/Texas%20Instruments/view-part/5674360/?ref=snap|Name=SnapEDA_Link
|RECORD=41|OwnerIndex=2265|IndexInSheet=7|OwnerPartId=-1|Location.X=1110|Location.Y=510|Color=8388608|FontID=1|IsHidden=T|Text=*|Name=Value
|RECORD=41|OwnerIndex=2265|IndexInSheet=8|OwnerPartId=-1|Location.X=1038|Location.Y=550|Color=8388608|FontID=1|IsHidden=T|Text=LCSC|Name=Supplier 1|ReadOnlyState=3
|RECORD=41|OwnerIndex=2265|IndexInSheet=9|OwnerPartId=-1|Location.X=1038|Location.Y=560|Color=8388608|FontID=1|IsHidden=T|Text=Texas Instruments|Name=Manufacturer
|RECORD=41|OwnerIndex=2265|IndexInSheet=10|OwnerPartId=-1|Location.X=1038|Location.Y=560|Color=8388608|FontID=1|IsHidden=T|Text=TPS2116DRLR|Name=Manufacturer Part Number
|RECORD=41|OwnerIndex=2265|IndexInSheet=11|OwnerPartId=-1|Location.X=1038|Location.Y=560|Color=8388608|FontID=1|IsHidden=T|Text=Yes|Name=RoHS
|RECORD=41|OwnerIndex=2265|IndexInSheet=12|OwnerPartId=-1|Location.X=1038|Location.Y=560|Color=8388608|FontID=1|IsHidden=T|Text=Voltage Supervisors|Name=Category
|RECORD=41|OwnerIndex=2265|IndexInSheet=13|OwnerPartId=-1|Location.X=1038|Location.Y=560|Color=8388608|FontID=1|IsHidden=T|Text=562|Name=Stock 1|ReadOnlyState=3
|RECORD=41|OwnerIndex=2265|IndexInSheet=14|OwnerPartId=-1|Location.X=1038|Location.Y=560|Color=8388608|FontID=1|IsHidden=T|Text=1=0.6651, 10=0.5457, 30=0.4853, 100=0.4264, 500=0.3914, 1000=0.3723 (USD)|Name=Pricing 1|ReadOnlyState=3
|RECORD=14|OwnerIndex=2265|IsNotAccesible=T|IndexInSheet=15|OwnerPartId=1|Location.X=1060|Location.Y=460|Corner.X=1160|Corner.Y=550|Color=128|AreaColor=11599871|IsSolid=T
|RECORD=2|OwnerIndex=2265|OwnerPartId=1|FormalType=1|Electrical=4|PinConglomerate=58|PinLength=20|Location.X=1060|Location.Y=540|Name=VIN1|Designator=3|SwapIDPart=Ž&Ž||PinPropagationDelay=0.000000E+000
|RECORD=2|OwnerIndex=2265|OwnerPartId=1|FormalType=1|Electrical=4|PinConglomerate=58|PinLength=20|Location.X=1060|Location.Y=530|Name=VIN2|Designator=6|SwapIDPart=Ž&Ž||PinPropagationDelay=0.000000E+000
|RECORD=2|OwnerIndex=2265|OwnerPartId=1|FormalType=1|Electrical=4|PinConglomerate=58|PinLength=20|Location.X=1060|Location.Y=510|Name=MODE|Designator=5|SwapIDPart=Ž&Ž||PinPropagationDelay=0.000000E+000
|RECORD=2|OwnerIndex=2265|OwnerPartId=1|FormalType=1|Electrical=4|PinConglomerate=58|PinLength=20|Location.X=1060|Location.Y=500|Name=PR1|Designator=4|SwapIDPart=Ž&Ž||PinPropagationDelay=0.000000E+000
|RECORD=2|OwnerIndex=2265|OwnerPartId=1|FormalType=1|Electrical=4|PinConglomerate=56|PinLength=20|Location.X=1160|Location.Y=540|Name=VOUT|Designator=2|SwapIDPart=Ž&Ž||PinPropagationDelay=0.000000E+000
|RECORD=2|OwnerIndex=2265|OwnerPartId=1|FormalType=1|Electrical=4|PinConglomerate=56|PinLength=20|Location.X=1160|Location.Y=530|Name=VOUT|Designator=7|SwapIDPart=Ž&Ž||PinPropagationDelay=0.000000E+000
|RECORD=2|OwnerIndex=2265|OwnerPartId=1|FormalType=1|Electrical=4|PinConglomerate=56|PinLength=20|Location.X=1160|Location.Y=500|Name=ST|Designator=8|SwapIDPart=Ž&Ž||PinPropagationDelay=0.000000E+000
|RECORD=2|OwnerIndex=2265|OwnerPartId=1|FormalType=1|Electrical=4|PinConglomerate=56|PinLength=20|Location.X=1160|Location.Y=470|Name=GND|Designator=1|SwapIDPart=Ž&Ž||PinPropagationDelay=0.000000E+000
|RECORD=41|OwnerIndex=2265|IndexInSheet=24|OwnerPartId=-1|Location.X=1038|Location.Y=550|Color=8388608|FontID=1|IsHidden=T|Text=C3235557|Name=Supplier Part Number 1|ReadOnlyState=3
|RECORD=34|OwnerIndex=2265|IndexInSheet=-1|OwnerPartId=-1|Location.X=1060|Location.Y=550|Color=8388608|FontID=1|Text=U34|Name=Designator|ReadOnlyState=1
|RECORD=41|OwnerIndex=2265|IndexInSheet=-1|OwnerPartId=-1|Location.X=1060|Location.Y=450|Color=8388608|FontID=1|Text=TPS2116DRLR|Name=Comment
|RECORD=44|OwnerIndex=2265
|RECORD=45|OwnerIndex=2301|IndexInSheet=-1|UseComponentLibrary=T|ModelName=IC_TPS2116|ModelType=PCBLIB|DatafileCount=1|ModelDatafileEntity0=IC_TPS2116|ModelDatafileKind0=PCBLib|IsCurrent=T|DatalinksLocked=T|DatabaseDatalinksLocked=T|IntegratedModel=T|DatabaseModel=T
|RECORD=46|OwnerIndex=2302
|RECORD=48|OwnerIndex=2302
|RECORD=1|LibReference=RES|PartCount=2|DisplayModeCount=2|IndexInSheet=294|OwnerPartId=-1|Location.X=950|Location.Y=500|Orientation=1|CurrentPartId=1|SourceLibraryName=Altium Content Vault|TargetFileName=*|AreaColor=11599871|Color=128|PartIDLocked=F|DesignItemId=CMP-2002-00433-1|AllPinCount=2
|RECORD=2|OwnerIndex=2305|OwnerPartId=1|OwnerPartDisplayMode=1|FormalType=1|Electrical=4|PinConglomerate=33|PinLength=10|Location.X=960|Location.Y=520|Name=2|Designator=2|PinPropagationDelay=0.000000E+000
|RECORD=2|OwnerIndex=2305|OwnerPartId=1|OwnerPartDisplayMode=1|FormalType=1|Electrical=4|PinConglomerate=35|PinLength=10|Location.X=960|Location.Y=500|Name=1|Designator=1|PinPropagationDelay=0.000000E+000
|RECORD=14|OwnerIndex=2305|IsNotAccesible=T|IndexInSheet=2|OwnerPartId=1|OwnerPartDisplayMode=1|Location.X=956|Location.Y=500|Corner.X=964|Corner.Y=520|LineWidth=1|Color=16711680|AreaColor=11599871
|RECORD=2|OwnerIndex=2305|OwnerPartId=1|FormalType=1|Electrical=4|PinConglomerate=33|PinLength=10|Location.X=960|Location.Y=520|Name=2|Designator=2|PinPropagationDelay=0.000000E+000
|RECORD=2|OwnerIndex=2305|OwnerPartId=1|FormalType=1|Electrical=4|PinConglomerate=35|PinLength=10|Location.X=960|Location.Y=500|Name=1|Designator=1|PinPropagationDelay=0.000000E+000
|RECORD=6|OwnerIndex=2305|IsNotAccesible=T|IndexInSheet=5|OwnerPartId=1|LineWidth=1|Color=16711680|LocationCount=10|X1=960|Y1=520|X2=960|Y2=516|X3=962|Y3=515|X4=958|Y4=513|X5=962|Y5=511|X6=958|Y6=509|X7=962|Y7=507|X8=958|Y8=505|X9=960|Y9=504|X10=960|Y10=500
|RECORD=41|OwnerIndex=2305|IndexInSheet=6|OwnerPartId=-1|Location.X=957|Location.Y=532|Color=8388608|FontID=1|IsHidden=T|Text=ERJ-2GEJ103X|Name=Part Number
|RECORD=41|OwnerIndex=2305|IndexInSheet=7|OwnerPartId=-1|Location.X=957|Location.Y=532|Color=8388608|FontID=1|IsHidden=T|Text=Panasonic|Name=Manufacturer
|RECORD=34|OwnerIndex=2305|IndexInSheet=-1|OwnerPartId=-1|Location.X=963|Location.Y=511|Color=8388608|FontID=1|Text=R180|Name=Designator|ReadOnlyState=1
|RECORD=41|OwnerIndex=2305|IndexInSheet=-1|OwnerPartId=-1|Location.X=963|Location.Y=501|Color=8388608|FontID=1|Text=10K_5%_0402|Name=Comment
|RECORD=44|OwnerIndex=2305
|RECORD=45|OwnerIndex=2320|IndexInSheet=-1|Description=Chip Resistor, 2-Leads, Body 1.00x0.50mm, IPC Low Density|UseComponentLibrary=T|ModelName=RESC1005X40X25ML05T05|ModelType=PCBLIB|DatafileCount=1|ModelDatafileEntity0=RESC1005X40X25ML05T05|ModelDatafileKind0=PCBLib|IsCurrent=T|DatalinksLocked=T|DatabaseDatalinksLocked=T
|RECORD=46|OwnerIndex=2321
|RECORD=48|OwnerIndex=2321
|RECORD=41|OwnerIndex=2323|IndexInSheet=-1|OwnerPartId=-1|Color=8388608|FontID=1|IsHidden=T|Text=2D|Name=Available Preview Images
|RECORD=45|OwnerIndex=2320|IndexInSheet=-1|Description=Chip Resistor, 2-Leads, Body 1.00x0.50mm, IPC Medium Density|UseComponentLibrary=T|ModelName=RESC1005X40X25NL05T05|ModelType=PCBLIB|DatafileCount=1|ModelDatafileEntity0=RESC1005X40X25NL05T05|ModelDatafileKind0=PCBLib|DatalinksLocked=T|DatabaseDatalinksLocked=T
|RECORD=46|OwnerIndex=2325
|RECORD=48|OwnerIndex=2325
|RECORD=41|OwnerIndex=2327|IndexInSheet=-1|OwnerPartId=-1|Color=8388608|FontID=1|IsHidden=T|Text=2D|Name=Available Preview Images
|RECORD=45|OwnerIndex=2320|IndexInSheet=-1|Description=Chip Resistor, 2-Leads, Body 1.00x0.50mm, IPC High Density|UseComponentLibrary=T|ModelName=RESC1005X40X25LL05T05|ModelType=PCBLIB|DatafileCount=1|ModelDatafileEntity0=RESC1005X40X25LL05T05|ModelDatafileKind0=PCBLib|DatalinksLocked=T|DatabaseDatalinksLocked=T
|RECORD=46|OwnerIndex=2329
|RECORD=48|OwnerIndex=2329
|RECORD=41|OwnerIndex=2331|IndexInSheet=-1|OwnerPartId=-1|Color=8388608|FontID=1|IsHidden=T|Text=2D|Name=Available Preview Images
|RECORD=1|LibReference=RES|PartCount=2|DisplayModeCount=2|IndexInSheet=295|OwnerPartId=-1|Location.X=950|Location.Y=440|Orientation=1|CurrentPartId=1|SourceLibraryName=Altium Content Vault|TargetFileName=*|AreaColor=11599871|Color=128|PartIDLocked=F|DesignItemId=CMP-2002-00433-1|AllPinCount=2
|RECORD=2|OwnerIndex=2333|OwnerPartId=1|OwnerPartDisplayMode=1|FormalType=1|Electrical=4|PinConglomerate=33|PinLength=10|Location.X=960|Location.Y=460|Name=2|Designator=2|PinPropagationDelay=0.000000E+000
|RECORD=2|OwnerIndex=2333|OwnerPartId=1|OwnerPartDisplayMode=1|FormalType=1|Electrical=4|PinConglomerate=35|PinLength=10|Location.X=960|Location.Y=440|Name=1|Designator=1|PinPropagationDelay=0.000000E+000
|RECORD=14|OwnerIndex=2333|IsNotAccesible=T|IndexInSheet=2|OwnerPartId=1|OwnerPartDisplayMode=1|Location.X=956|Location.Y=440|Corner.X=964|Corner.Y=460|LineWidth=1|Color=16711680|AreaColor=11599871
|RECORD=2|OwnerIndex=2333|OwnerPartId=1|FormalType=1|Electrical=4|PinConglomerate=33|PinLength=10|Location.X=960|Location.Y=460|Name=2|Designator=2|PinPropagationDelay=0.000000E+000
|RECORD=2|OwnerIndex=2333|OwnerPartId=1|FormalType=1|Electrical=4|PinConglomerate=35|PinLength=10|Location.X=960|Location.Y=440|Name=1|Designator=1|PinPropagationDelay=0.000000E+000
|RECORD=6|OwnerIndex=2333|IsNotAccesible=T|IndexInSheet=5|OwnerPartId=1|LineWidth=1|Color=16711680|LocationCount=10|X1=960|Y1=460|X2=960|Y2=456|X3=962|Y3=455|X4=958|Y4=453|X5=962|Y5=451|X6=958|Y6=449|X7=962|Y7=447|X8=958|Y8=445|X9=960|Y9=444|X10=960|Y10=440
|RECORD=41|OwnerIndex=2333|IndexInSheet=6|OwnerPartId=-1|Location.X=957|Location.Y=472|Color=8388608|FontID=1|IsHidden=T|Text=ERJ-2GEJ103X|Name=Part Number
|RECORD=41|OwnerIndex=2333|IndexInSheet=7|OwnerPartId=-1|Location.X=957|Location.Y=472|Color=8388608|FontID=1|IsHidden=T|Text=Panasonic|Name=Manufacturer
|RECORD=34|OwnerIndex=2333|IndexInSheet=-1|OwnerPartId=-1|Location.X=963|Location.Y=451|Color=8388608|FontID=1|Text=R182|Name=Designator|ReadOnlyState=1
|RECORD=41|OwnerIndex=2333|IndexInSheet=-1|OwnerPartId=-1|Location.X=963|Location.Y=441|Color=8388608|FontID=1|Text=10K_5%_0402|Name=Comment
|RECORD=44|OwnerIndex=2333
|RECORD=45|OwnerIndex=2348|IndexInSheet=-1|Description=Chip Resistor, 2-Leads, Body 1.00x0.50mm, IPC Low Density|UseComponentLibrary=T|ModelName=RESC1005X40X25ML05T05|ModelType=PCBLIB|DatafileCount=1|ModelDatafileEntity0=RESC1005X40X25ML05T05|ModelDatafileKind0=PCBLib|IsCurrent=T|DatalinksLocked=T|DatabaseDatalinksLocked=T
|RECORD=46|OwnerIndex=2349
|RECORD=48|OwnerIndex=2349
|RECORD=41|OwnerIndex=2351|IndexInSheet=-1|OwnerPartId=-1|Color=8388608|FontID=1|IsHidden=T|Text=2D|Name=Available Preview Images
|RECORD=45|OwnerIndex=2348|IndexInSheet=-1|Description=Chip Resistor, 2-Leads, Body 1.00x0.50mm, IPC Medium Density|UseComponentLibrary=T|ModelName=RESC1005X40X25NL05T05|ModelType=PCBLIB|DatafileCount=1|ModelDatafileEntity0=RESC1005X40X25NL05T05|ModelDatafileKind0=PCBLib|DatalinksLocked=T|DatabaseDatalinksLocked=T
|RECORD=46|OwnerIndex=2353
|RECORD=48|OwnerIndex=2353
|RECORD=41|OwnerIndex=2355|IndexInSheet=-1|OwnerPartId=-1|Color=8388608|FontID=1|IsHidden=T|Text=2D|Name=Available Preview Images
|RECORD=45|OwnerIndex=2348|IndexInSheet=-1|Description=Chip Resistor, 2-Leads, Body 1.00x0.50mm, IPC High Density|UseComponentLibrary=T|ModelName=RESC1005X40X25LL05T05|ModelType=PCBLIB|DatafileCount=1|ModelDatafileEntity0=RESC1005X40X25LL05T05|ModelDatafileKind0=PCBLib|DatalinksLocked=T|DatabaseDatalinksLocked=T
|RECORD=46|OwnerIndex=2357
|RECORD=48|OwnerIndex=2357
|RECORD=41|OwnerIndex=2359|IndexInSheet=-1|OwnerPartId=-1|Color=8388608|FontID=1|IsHidden=T|Text=2D|Name=Available Preview Images
|RECORD=17|IndexInSheet=296|OwnerPartId=-1|Style=4|ShowNetName=T|Location.X=960|Location.Y=430|Orientation=3|Color=128|FontID=1|Text=GND
|RECORD=17|IndexInSheet=297|OwnerPartId=-1|Style=4|ShowNetName=T|Location.X=1190|Location.Y=450|Orientation=3|Color=128|FontID=1|Text=GND
|RECORD=1|LibReference=b4654b650e69147ec39a6b967a45e02|ComponentDescription=General Purpose Ceramic Capacitor, 0402, 100nF, 10%, X7R, 15%, 25V|PartCount=2|DisplayModeCount=1|IndexInSheet=298|OwnerPartId=-1|Location.X=1220|Location.Y=530|CurrentPartId=1|LibraryPath=*|SourceLibraryName=Altium Content Vault|TargetFileName=*|AreaColor=11599871|Color=128|PartIDLocked=T|DesignItemId=CMP-2008-02519-2|AllPinCount=2
|RECORD=2|OwnerIndex=2363|OwnerPartId=1|Electrical=4|PinConglomerate=49|PinLength=7|Location.X=1220|Location.Y=523|Name=1|Designator=1|PinPropagationDelay=0.000000E+000
|RECORD=2|OwnerIndex=2363|OwnerPartId=1|Electrical=4|PinConglomerate=51|PinLength=6|Location.X=1220|Location.Y=516|Name=2|Designator=2|PinPropagationDelay=0.000000E+000
|RECORD=13|OwnerIndex=2363|IsNotAccesible=T|IndexInSheet=2|OwnerPartId=1|Location.X=1230|Location.Y=523|Corner.X=1210|Corner.Y=523|LineWidth=1|Color=16711680
|RECORD=13|OwnerIndex=2363|IsNotAccesible=T|IndexInSheet=3|OwnerPartId=1|Location.X=1230|Location.Y=517|Corner.X=1210|Corner.Y=517|LineWidth=1|Color=16711680
|RECORD=13|OwnerIndex=2363|IsNotAccesible=T|IndexInSheet=4|OwnerPartId=1|Location.X=1220|Location.Y=523|Corner.X=1220|Corner.Y=526|LineWidth=1|Color=16711680
|RECORD=13|OwnerIndex=2363|IsNotAccesible=T|IndexInSheet=5|OwnerPartId=1|Location.X=1220|Location.Y=516|Corner.X=1220|Corner.Y=515|LineWidth=1|Color=16711680
|RECORD=41|OwnerIndex=2363|IndexInSheet=6|OwnerPartId=-1|Location.X=1209|Location.Y=532|Color=8388608|FontID=1|IsHidden=T|Text=1|Name=Package Quantity
|RECORD=41|OwnerIndex=2363|IndexInSheet=7|OwnerPartId=-1|Location.X=1209|Location.Y=532|Color=8388608|FontID=1|IsHidden=T|Text=100nF|Name=Capacitance
|RECORD=41|OwnerIndex=2363|IndexInSheet=8|OwnerPartId=-1|Location.X=1209|Location.Y=532|Color=8388608|FontID=1|IsHidden=T|Text=-55°C|Name=Min Operating Temperature
|RECORD=41|OwnerIndex=2363|IndexInSheet=9|OwnerPartId=-1|Location.X=1209|Location.Y=532|Color=8388608|FontID=1|IsHidden=T|Text=25V|Name=Voltage
|RECORD=41|OwnerIndex=2363|IndexInSheet=10|OwnerPartId=-1|Location.X=1209|Location.Y=532|Color=8388608|FontID=1|IsHidden=T|Text=25V|Name=Voltage Rating
|RECORD=41|OwnerIndex=2363|IndexInSheet=11|OwnerPartId=-1|Location.X=1209|Location.Y=532|Color=8388608|FontID=1|IsHidden=T|Text=Flat|Name=Construction
|RECORD=41|OwnerIndex=2363|IndexInSheet=12|OwnerPartId=-1|Location.X=1209|Location.Y=532|Color=8388608|FontID=1|IsHidden=T|Text=125°C|Name=Max Operating Temperature
|RECORD=41|OwnerIndex=2363|IndexInSheet=13|OwnerPartId=-1|Location.X=1209|Location.Y=532|Color=8388608|FontID=1|IsHidden=T|Text=No|Name=Radiation Hardening
|RECORD=41|OwnerIndex=2363|IndexInSheet=14|OwnerPartId=-1|Location.X=1209|Location.Y=532|Color=8388608|FontID=1|IsHidden=T|Text=0.5mm|Name=Depth
|RECORD=41|OwnerIndex=2363|IndexInSheet=15|OwnerPartId=-1|Location.X=1209|Location.Y=532|Color=8388608|FontID=1|IsHidden=T|Text=0.022inch|Name=Thickness
|RECORD=41|OwnerIndex=2363|IndexInSheet=16|OwnerPartId=-1|Location.X=1209|Location.Y=532|Color=8388608|FontID=1|IsHidden=T|Text=25V|Name=Voltage Rating (DC)
|RECORD=41|OwnerIndex=2363|IndexInSheet=17|OwnerPartId=-1|Location.X=1209|Location.Y=532|Color=8388608|FontID=1|IsHidden=T|Text=2|Name=Number of Pins
|RECORD=41|OwnerIndex=2363|IndexInSheet=18|OwnerPartId=-1|Location.X=1209|Location.Y=532|Color=8388608|FontID=1|IsHidden=T|Text=Lead Free|Name=Lead Free
|RECORD=41|OwnerIndex=2363|IndexInSheet=19|OwnerPartId=-1|Location.X=1209|Location.Y=532|Color=8388608|FontID=1|IsHidden=T|Text=-|Name=Series
|RECORD=41|OwnerIndex=2363|IndexInSheet=20|OwnerPartId=-1|Location.X=1209|Location.Y=532|Color=8388608|FontID=1|IsHidden=T|Text=No SVHC|Name=REACH SVHC
|RECORD=41|OwnerIndex=2363|IndexInSheet=21|OwnerPartId=-1|Location.X=1209|Location.Y=532|Color=8388608|FontID=1|IsHidden=T|Text=1mm|Name=Length
|RECORD=41|OwnerIndex=2363|IndexInSheet=22|OwnerPartId=-1|Location.X=1209|Location.Y=532|Color=8388608|FontID=1|IsHidden=T|Text=X7R|Name=Dielectric
|RECORD=41|OwnerIndex=2363|IndexInSheet=23|OwnerPartId=-1|Location.X=1209|Location.Y=532|Color=8388608|FontID=1|IsHidden=T|Text=Yes|Name=RoHS Compliant
|RECORD=41|OwnerIndex=2363|IndexInSheet=24|OwnerPartId=-1|Location.X=1209|Location.Y=532|Color=8388608|FontID=1|IsHidden=T|Text=Surface Mount|Name=Mount
|RECORD=41|OwnerIndex=2363|IndexInSheet=25|OwnerPartId=-1|Location.X=1209|Location.Y=532|Color=8388608|FontID=1|IsHidden=T|Text=Tape and Reel|Name=Packaging
|RECORD=41|OwnerIndex=2363|IndexInSheet=26|OwnerPartId=-1|Location.X=1209|Location.Y=532|Color=8388608|FontID=1|IsHidden=T|Text=0402|Name=Case/Package
|RECORD=41|OwnerIndex=2363|IndexInSheet=27|OwnerPartId=-1|Location.X=1209|Location.Y=532|Color=8388608|FontID=1|IsHidden=T|Text=0402|Name=Case Code (Imperial)
|RECORD=41|OwnerIndex=2363|IndexInSheet=28|OwnerPartId=-1|Location.X=1209|Location.Y=532|Color=8388608|FontID=1|IsHidden=T|Text=SMD/SMT|Name=Termination
|RECORD=41|OwnerIndex=2363|IndexInSheet=29|OwnerPartId=-1|Location.X=1209|Location.Y=532|Color=8388608|FontID=1|IsHidden=T|Text=0.02inch|Name=Width
|RECORD=41|OwnerIndex=2363|IndexInSheet=30|OwnerPartId=-1|Location.X=1209|Location.Y=532|Color=8388608|FontID=1|IsHidden=T|Text=1005|Name=Case Code (Metric)
|RECORD=41|OwnerIndex=2363|IndexInSheet=31|OwnerPartId=-1|Location.X=1209|Location.Y=532|Color=8388608|FontID=1|IsHidden=T|Text=10%|Name=Tolerance
|RECORD=34|OwnerIndex=2363|IndexInSheet=-1|OwnerPartId=-1|Location.X=1210|Location.Y=510|Orientation=1|Color=8388608|FontID=2|Text=C113|Name=Designator|ReadOnlyState=1
|RECORD=41|OwnerIndex=2363|IndexInSheet=-1|OwnerPartId=1|Location.X=1240|Location.Y=495|Orientation=1|Color=8388608|FontID=2|Text=0.1uF_25V_0402|Name=Comment
|RECORD=44|OwnerIndex=2363
|RECORD=45|OwnerIndex=2400|IndexInSheet=-1|UseComponentLibrary=T|ModelName=FP-0402-L_1_0_1-W_0_5_0_1-IPC_C|ModelType=PCBLIB|DatafileCount=1|ModelDatafileEntity0=FP-0402-L_1_0_1-W_0_5_0_1-IPC_C|ModelDatafileKind0=PCBLib|IsCurrent=T|DatalinksLocked=T|DatabaseDatalinksLocked=T
|RECORD=46|OwnerIndex=2401
|RECORD=48|OwnerIndex=2401
|RECORD=45|OwnerIndex=2400|IndexInSheet=-1|UseComponentLibrary=T|ModelName=FP-0402-L_1_0_1-W_0_5_0_1-IPC_B|ModelType=PCBLIB|DatafileCount=1|ModelDatafileEntity0=FP-0402-L_1_0_1-W_0_5_0_1-IPC_B|ModelDatafileKind0=PCBLib|DatalinksLocked=T|DatabaseDatalinksLocked=T
|RECORD=46|OwnerIndex=2404
|RECORD=48|OwnerIndex=2404
|RECORD=45|OwnerIndex=2400|IndexInSheet=-1|UseComponentLibrary=T|ModelName=FP-0402-L_1_0_1-W_0_5_0_1-MFG|ModelType=PCBLIB|DatafileCount=1|ModelDatafileEntity0=FP-0402-L_1_0_1-W_0_5_0_1-MFG|ModelDatafileKind0=PCBLib|DatalinksLocked=T|DatabaseDatalinksLocked=T
|RECORD=46|OwnerIndex=2407
|RECORD=48|OwnerIndex=2407
|RECORD=45|OwnerIndex=2400|IndexInSheet=-1|UseComponentLibrary=T|ModelName=FP-0402-L_1_0_1-W_0_5_0_1-IPC_A|ModelType=PCBLIB|DatafileCount=1|ModelDatafileEntity0=FP-0402-L_1_0_1-W_0_5_0_1-IPC_A|ModelDatafileKind0=PCBLib|DatalinksLocked=T|DatabaseDatalinksLocked=T
|RECORD=46|OwnerIndex=2410
|RECORD=48|OwnerIndex=2410
|RECORD=17|IndexInSheet=299|OwnerPartId=-1|ShowNetName=T|Location.X=1270|Location.Y=550|Orientation=1|Color=128|FontID=1|Text=GNSS2_P5V0
|RECORD=27|IndexInSheet=300|OwnerPartId=-1|LineWidth=1|Color=8388608|LocationCount=3|X1=1040|Y1=530|X2=1030|Y2=530|X3=1030|Y3=550
|RECORD=27|IndexInSheet=301|OwnerPartId=-1|LineWidth=1|Color=8388608|LocationCount=3|X1=1040|Y1=510|X2=1010|Y2=510|X3=1010|Y3=540
|RECORD=27|IndexInSheet=302|OwnerPartId=-1|LineWidth=1|Color=8388608|LocationCount=3|X1=1180|Y1=470|X2=1190|Y2=470|X3=1190|Y3=450
|RECORD=27|IndexInSheet=303|OwnerPartId=-1|LineWidth=1|Color=8388608|LocationCount=2|X1=1180|Y1=540|X2=1190|Y2=540
|RECORD=27|IndexInSheet=304|OwnerPartId=-1|LineWidth=1|Color=8388608|LocationCount=3|X1=1220|Y1=510|X2=1220|Y2=470|X3=1190|Y3=470
|RECORD=27|IndexInSheet=305|OwnerPartId=-1|LineWidth=1|Color=8388608|LocationCount=2|X1=1220|Y1=530|X2=1220|Y2=540
|RECORD=27|IndexInSheet=306|OwnerPartId=-1|LineWidth=1|Color=8388608|LocationCount=5|X1=960|Y1=470|X2=960|Y2=480|X3=1000|Y3=480|X4=1000|Y4=500|X5=1040|Y5=500
|RECORD=27|IndexInSheet=307|OwnerPartId=-1|LineWidth=1|Color=8388608|LocationCount=2|X1=960|Y1=490|X2=960|Y2=480
|RECORD=27|IndexInSheet=308|OwnerPartId=-1|LineWidth=1|Color=8388608|LocationCount=4|X1=960|Y1=530|X2=960|Y2=540|X3=980|Y3=540|X4=980|Y4=550
|RECORD=27|IndexInSheet=309|OwnerPartId=-1|LineWidth=1|Color=8388608|LocationCount=3|X1=980|Y1=540|X2=1010|Y2=540|X3=1040|Y3=540
|RECORD=27|IndexInSheet=310|OwnerPartId=-1|LineWidth=1|Color=8388608|LocationCount=6|X1=1180|Y1=530|X2=1190|Y2=530|X3=1190|Y3=540|X4=1220|Y4=540|X5=1270|Y5=540|X6=1270|Y6=550
|RECORD=17|IndexInSheet=311|OwnerPartId=-1|ShowNetName=T|Location.X=1030|Location.Y=550|Orientation=1|Color=128|FontID=1|Text=FTDI_VBUS
|RECORD=17|IndexInSheet=312|OwnerPartId=-1|ShowNetName=T|Location.X=980|Location.Y=550|Orientation=1|Color=128|FontID=1|Text=+5.0V
|RECORD=29|IndexInSheet=-1|OwnerPartId=-1|Location.X=70|Location.Y=480|Color=128
|RECORD=29|IndexInSheet=-1|OwnerPartId=-1|Location.X=70|Location.Y=550|Color=128
|RECORD=29|IndexInSheet=-1|OwnerPartId=-1|Location.X=110|Location.Y=550|Color=128
|RECORD=29|IndexInSheet=-1|OwnerPartId=-1|Location.X=170|Location.Y=550|Color=128
|RECORD=29|IndexInSheet=-1|OwnerPartId=-1|Location.X=180|Location.Y=720|Color=128
|RECORD=29|IndexInSheet=-1|OwnerPartId=-1|Location.X=180|Location.Y=730|Color=128
|RECORD=29|IndexInSheet=-1|OwnerPartId=-1|Location.X=180|Location.Y=740|Color=128
|RECORD=29|IndexInSheet=-1|OwnerPartId=-1|Location.X=180|Location.Y=750|Color=128
|RECORD=29|IndexInSheet=-1|OwnerPartId=-1|Location.X=180|Location.Y=760|Color=128
|RECORD=29|IndexInSheet=-1|OwnerPartId=-1|Location.X=180|Location.Y=770|Color=128
|RECORD=29|IndexInSheet=-1|OwnerPartId=-1|Location.X=180|Location.Y=780|Color=128
|RECORD=29|IndexInSheet=-1|OwnerPartId=-1|Location.X=220|Location.Y=720|Color=128
|RECORD=29|IndexInSheet=-1|OwnerPartId=-1|Location.X=240|Location.Y=850|Color=128
|RECORD=29|IndexInSheet=-1|OwnerPartId=-1|Location.X=260|Location.Y=720|Color=128
|RECORD=29|IndexInSheet=-1|OwnerPartId=-1|Location.X=260|Location.Y=810|Color=128
|RECORD=29|IndexInSheet=-1|OwnerPartId=-1|Location.X=300|Location.Y=720|Color=128
|RECORD=29|IndexInSheet=-1|OwnerPartId=-1|Location.X=300|Location.Y=830|Color=128
|RECORD=29|IndexInSheet=-1|OwnerPartId=-1|Location.X=310|Location.Y=480|Color=128
|RECORD=29|IndexInSheet=-1|OwnerPartId=-1|Location.X=340|Location.Y=550|Color=128
|RECORD=29|IndexInSheet=-1|OwnerPartId=-1|Location.X=340|Location.Y=720|Color=128
|RECORD=29|IndexInSheet=-1|OwnerPartId=-1|Location.X=340|Location.Y=850|Color=128
|RECORD=29|IndexInSheet=-1|OwnerPartId=-1|Location.X=380|Location.Y=850|Color=128
|RECORD=29|IndexInSheet=-1|OwnerPartId=-1|Location.X=390|Location.Y=360|Color=128
|RECORD=29|IndexInSheet=-1|OwnerPartId=-1|Location.X=390|Location.Y=500|Color=128
|RECORD=29|IndexInSheet=-1|OwnerPartId=-1|Location.X=390|Location.Y=550|Color=128
|RECORD=29|IndexInSheet=-1|OwnerPartId=-1|Location.X=400|Location.Y=850|Color=128
|RECORD=29|IndexInSheet=-1|OwnerPartId=-1|Location.X=430|Location.Y=150|Color=128
|RECORD=29|IndexInSheet=-1|OwnerPartId=-1|Location.X=430|Location.Y=200|Color=128
|RECORD=29|IndexInSheet=-1|OwnerPartId=-1|Location.X=430|Location.Y=550|Color=128
|RECORD=29|IndexInSheet=-1|OwnerPartId=-1|Location.X=490|Location.Y=690|Color=128
|RECORD=29|IndexInSheet=-1|OwnerPartId=-1|Location.X=490|Location.Y=770|Color=128
|RECORD=29|IndexInSheet=-1|OwnerPartId=-1|Location.X=490|Location.Y=790|Color=128
|RECORD=29|IndexInSheet=-1|OwnerPartId=-1|Location.X=550|Location.Y=680|Color=128
|RECORD=29|IndexInSheet=-1|OwnerPartId=-1|Location.X=550|Location.Y=750|Color=128
|RECORD=29|IndexInSheet=-1|OwnerPartId=-1|Location.X=550|Location.Y=770|Color=128
|RECORD=29|IndexInSheet=-1|OwnerPartId=-1|Location.X=580|Location.Y=510|Color=128
|RECORD=29|IndexInSheet=-1|OwnerPartId=-1|Location.X=600|Location.Y=280|Color=128
|RECORD=29|IndexInSheet=-1|OwnerPartId=-1|Location.X=600|Location.Y=340|Color=128
|RECORD=29|IndexInSheet=-1|OwnerPartId=-1|Location.X=600|Location.Y=570|Color=128
|RECORD=29|IndexInSheet=-1|OwnerPartId=-1|Location.X=630|Location.Y=240|Color=128
|RECORD=29|IndexInSheet=-1|OwnerPartId=-1|Location.X=630|Location.Y=320|Color=128
|RECORD=29|IndexInSheet=-1|OwnerPartId=-1|Location.X=630|Location.Y=570|Color=128
|RECORD=29|IndexInSheet=-1|OwnerPartId=-1|Location.X=750|Location.Y=770|Color=128
|RECORD=29|IndexInSheet=-1|OwnerPartId=-1|Location.X=810|Location.Y=500|Color=128
|RECORD=29|IndexInSheet=-1|OwnerPartId=-1|Location.X=810|Location.Y=570|Color=128
|RECORD=29|IndexInSheet=-1|OwnerPartId=-1|Location.X=840|Location.Y=570|Color=128
|RECORD=29|IndexInSheet=-1|OwnerPartId=-1|Location.X=960|Location.Y=480|Color=128
|RECORD=29|IndexInSheet=-1|OwnerPartId=-1|Location.X=980|Location.Y=540|Color=128
|RECORD=29|IndexInSheet=-1|OwnerPartId=-1|Location.X=1010|Location.Y=540|Color=128
|RECORD=29|IndexInSheet=-1|OwnerPartId=-1|Location.X=1140|Location.Y=850|Color=128
|RECORD=29|IndexInSheet=-1|OwnerPartId=-1|Location.X=1150|Location.Y=370|Color=128
|RECORD=29|IndexInSheet=-1|OwnerPartId=-1|Location.X=1180|Location.Y=640|Color=128
|RECORD=29|IndexInSheet=-1|OwnerPartId=-1|Location.X=1180|Location.Y=690|Color=128
|RECORD=29|IndexInSheet=-1|OwnerPartId=-1|Location.X=1190|Location.Y=160|Color=128
|RECORD=29|IndexInSheet=-1|OwnerPartId=-1|Location.X=1190|Location.Y=210|Color=128
|RECORD=29|IndexInSheet=-1|OwnerPartId=-1|Location.X=1190|Location.Y=470|Color=128
|RECORD=29|IndexInSheet=-1|OwnerPartId=-1|Location.X=1190|Location.Y=540|Color=128
|RECORD=29|IndexInSheet=-1|OwnerPartId=-1|Location.X=1220|Location.Y=540|Color=128
|RECORD=29|IndexInSheet=-1|OwnerPartId=-1|Location.X=1360|Location.Y=770|Color=128
|RECORD=29|IndexInSheet=-1|OwnerPartId=-1|Location.X=1370|Location.Y=290|Color=128
|RECORD=29|IndexInSheet=-1|OwnerPartId=-1|Location.X=1370|Location.Y=730|Color=128
|RECORD=29|IndexInSheet=-1|OwnerPartId=-1|Location.X=1390|Location.Y=250|Color=128